G04 ================== begin FILE IDENTIFICATION RECORD ==================*
G04 Layout Name:  9048_F0T_Management_Board_D_brd_V04_1213_1625.brd*
G04 Film Name:    vcc1*
G04 File Format:  Gerber RS274X*
G04 File Origin:  Cadence Allegro 17.2-S081*
G04 Origin Date:  Tue Dec 13 16:31:10 2022*
G04 *
G04 Layer:  DRAWING FORMAT/TITLE_BLOCK_A*
G04 Layer:  DRAWING FORMAT/TITLE_BLOCK*
G04 Layer:  VIA CLASS/VCC1*
G04 Layer:  PIN/VCC1*
G04 Layer:  MANUFACTURING/PHOTOPLOT_OUTLINE*
G04 Layer:  ETCH/VCC1*
G04 Layer:  DRAWING FORMAT/TITLE_DATA_VCC1*
G04 *
G04 Offset:    (0.00 0.00)*
G04 Mirror:    No*
G04 Mode:      Negative*
G04 Rotation:  0*
G04 FullContactRelief:  No*
G04 UndefLineWidth:     6.00*
G04 ================== end FILE IDENTIFICATION RECORD ====================*
%FSLAX25Y25*MOIN*%
%IR0*IPPOS*OFA0.00000B0.00000*MIA0B0*SFA1.00000B1.00000*%
%ADD14C,.03*%
%ADD24C,.052*%
%ADD22C,.061*%
%ADD36C,.071*%
%ADD27C,.026*%
%AMMACRO34*
4,1,36,.0025,0.0,
.002462,.000434,
.002349,.000855,
.002165,.00125,
.001915,.001607,
.001607,.001915,
.00125,.002165,
.000855,.002349,
.000434,.002462,
0.0,.0025,
-.000434,.002462,
-.000855,.002349,
-.00125,.002165,
-.001607,.001915,
-.001915,.001607,
-.002165,.00125,
-.002349,.000855,
-.002462,.000434,
-.0025,0.0,
-.002462,-.000434,
-.002349,-.000855,
-.002165,-.00125,
-.001915,-.001607,
-.001607,-.001915,
-.00125,-.002165,
-.000855,-.002349,
-.000434,-.002462,
0.0,-.0025,
.000434,-.002462,
.000855,-.002349,
.00125,-.002165,
.001607,-.001915,
.001915,-.001607,
.002165,-.00125,
.002349,-.000855,
.002462,-.000434,
.0025,0.0,
315.*
%
%ADD34MACRO34*%
%AMMACRO23*
4,1,36,.0025,0.0,
.002462,.000434,
.002349,.000855,
.002165,.00125,
.001915,.001607,
.001607,.001915,
.00125,.002165,
.000855,.002349,
.000434,.002462,
0.0,.0025,
-.000434,.002462,
-.000855,.002349,
-.00125,.002165,
-.001607,.001915,
-.001915,.001607,
-.002165,.00125,
-.002349,.000855,
-.002462,.000434,
-.0025,0.0,
-.002462,-.000434,
-.002349,-.000855,
-.002165,-.00125,
-.001915,-.001607,
-.001607,-.001915,
-.00125,-.002165,
-.000855,-.002349,
-.000434,-.002462,
0.0,-.0025,
.000434,-.002462,
.000855,-.002349,
.00125,-.002165,
.001607,-.001915,
.001915,-.001607,
.002165,-.00125,
.002349,-.000855,
.002462,-.000434,
.0025,0.0,
180.*
%
%ADD23MACRO23*%
%AMMACRO21*
4,1,36,.0025,0.0,
.002462,.000434,
.002349,.000855,
.002165,.00125,
.001915,.001607,
.001607,.001915,
.00125,.002165,
.000855,.002349,
.000434,.002462,
0.0,.0025,
-.000434,.002462,
-.000855,.002349,
-.00125,.002165,
-.001607,.001915,
-.001915,.001607,
-.002165,.00125,
-.002349,.000855,
-.002462,.000434,
-.0025,0.0,
-.002462,-.000434,
-.002349,-.000855,
-.002165,-.00125,
-.001915,-.001607,
-.001607,-.001915,
-.00125,-.002165,
-.000855,-.002349,
-.000434,-.002462,
0.0,-.0025,
.000434,-.002462,
.000855,-.002349,
.00125,-.002165,
.001607,-.001915,
.001915,-.001607,
.002165,-.00125,
.002349,-.000855,
.002462,-.000434,
.0025,0.0,
270.*
%
%ADD21MACRO21*%
%AMMACRO38*
4,1,36,.003,0.0,
.002954,.000521,
.002819,.001026,
.002598,.0015,
.002298,.001928,
.001928,.002298,
.0015,.002598,
.001026,.002819,
.000521,.002954,
0.0,.003,
-.000521,.002954,
-.001026,.002819,
-.0015,.002598,
-.001928,.002298,
-.002298,.001928,
-.002598,.0015,
-.002819,.001026,
-.002954,.000521,
-.003,0.0,
-.002954,-.000521,
-.002819,-.001026,
-.002598,-.0015,
-.002298,-.001928,
-.001928,-.002298,
-.0015,-.002598,
-.001026,-.002819,
-.000521,-.002954,
0.0,-.003,
.000521,-.002954,
.001026,-.002819,
.0015,-.002598,
.001928,-.002298,
.002298,-.001928,
.002598,-.0015,
.002819,-.001026,
.002954,-.000521,
.003,0.0,
270.*
%
%ADD38MACRO38*%
%AMMACRO41*
4,1,36,-.003,0.0,
-.002954,.000521,
-.002819,.001026,
-.002598,.0015,
-.002298,.001928,
-.001928,.002298,
-.0015,.002598,
-.001026,.002819,
-.000521,.002954,
0.0,.003,
.000521,.002954,
.001026,.002819,
.0015,.002598,
.001928,.002298,
.002298,.001928,
.002598,.0015,
.002819,.001026,
.002954,.000521,
.003,0.0,
.002954,-.000521,
.002819,-.001026,
.002598,-.0015,
.002298,-.001928,
.001928,-.002298,
.0015,-.002598,
.001026,-.002819,
.000521,-.002954,
0.0,-.003,
-.000521,-.002954,
-.001026,-.002819,
-.0015,-.002598,
-.001928,-.002298,
-.002298,-.001928,
-.002598,-.0015,
-.002819,-.001026,
-.002954,-.000521,
-.003,0.0,
270.*
%
%ADD41MACRO41*%
%ADD37C,.0435*%
%ADD31C,.048*%
%ADD15C,.066*%
%ADD26C,.078*%
%ADD11C,.087*%
%ADD32C,.097*%
%AMMACRO25*
4,1,15,.02475,.01414,
.026829,.009627,
.028094,.004822,
.028504,-.000129,
.028049,-.005077,
.026741,-.009871,
.02475,-.01414,
.02984,-.01923,
.032726,-.013756,
.034617,-.007864,
.035457,-.001734,
.03522,.00445,
.033912,.010498,
.031574,.016227,
.02984,.01923,
.02475,.01414,
0.0*
4,1,15,.01414,-.02475,
.009627,-.026829,
.004822,-.028094,
-.000129,-.028504,
-.005077,-.028049,
-.009871,-.026741,
-.01414,-.02475,
-.01923,-.02984,
-.013756,-.032726,
-.007864,-.034617,
-.001734,-.035457,
.00445,-.03522,
.010498,-.033912,
.016227,-.031574,
.01923,-.02984,
.01414,-.02475,
0.0*
4,1,15,-.02475,-.01414,
-.026829,-.009627,
-.028094,-.004822,
-.028504,.000129,
-.028049,.005077,
-.026741,.009871,
-.02475,.01414,
-.02984,.01923,
-.032726,.013756,
-.034617,.007864,
-.035457,.001734,
-.03522,-.00445,
-.033912,-.010498,
-.031574,-.016227,
-.02984,-.01923,
-.02475,-.01414,
0.0*
4,1,15,-.01414,.02475,
-.009627,.026829,
-.004822,.028094,
.000129,.028504,
.005077,.028049,
.009871,.026741,
.01414,.02475,
.01923,.02984,
.013756,.032726,
.007864,.034617,
.001734,.035457,
-.00445,.03522,
-.010498,.033912,
-.016227,.031574,
-.01923,.02984,
-.01414,.02475,
0.0*
%
%ADD25MACRO25*%
%AMMACRO10*
4,1,15,.03682,.01914,
.039584,.012455,
.041146,.005393,
.041457,-.001834,
.040509,-.009005,
.03833,-.015903,
.03682,-.01914,
.04197,-.0243,
.045552,-.016643,
.04775,-.00848,
.048497,-.000059,
.047771,.008363,
.045593,.016531,
.042029,.024197,
.04197,.0243,
.03682,.01914,
0.0*
4,1,15,.01914,-.03682,
.012455,-.039584,
.005393,-.041146,
-.001834,-.041457,
-.009005,-.040509,
-.015903,-.03833,
-.01914,-.03682,
-.0243,-.04197,
-.016643,-.045552,
-.00848,-.04775,
-.000059,-.048497,
.008363,-.047771,
.016531,-.045593,
.024197,-.042029,
.0243,-.04197,
.01914,-.03682,
0.0*
4,1,15,-.03682,-.01914,
-.039584,-.012455,
-.041146,-.005393,
-.041457,.001834,
-.040509,.009005,
-.03833,.015903,
-.03682,.01914,
-.04197,.0243,
-.045552,.016643,
-.04775,.00848,
-.048497,.000059,
-.047771,-.008363,
-.045593,-.016531,
-.042029,-.024197,
-.04197,-.0243,
-.03682,-.01914,
0.0*
4,1,15,-.01914,.03682,
-.012455,.039584,
-.005393,.041146,
.001834,.041457,
.009005,.040509,
.015903,.03833,
.01914,.03682,
.0243,.04197,
.016643,.045552,
.00848,.04775,
.000059,.048497,
-.008363,.047771,
-.016531,.045593,
-.024197,.042029,
-.0243,.04197,
-.01914,.03682,
0.0*
%
%ADD10MACRO10*%
%ADD30C,.111*%
%ADD29C,.17*%
%ADD28O,.156X.219*%
%ADD17C,.144*%
%ADD33C,.154*%
%ADD20C,.155*%
%ADD16C,.146*%
%AMMACRO35*
4,1,36,.0025,0.0,
.002462,.000434,
.002349,.000855,
.002165,.00125,
.001915,.001607,
.001607,.001915,
.00125,.002165,
.000855,.002349,
.000434,.002462,
0.0,.0025,
-.000434,.002462,
-.000855,.002349,
-.00125,.002165,
-.001607,.001915,
-.001915,.001607,
-.002165,.00125,
-.002349,.000855,
-.002462,.000434,
-.0025,0.0,
-.002462,-.000434,
-.002349,-.000855,
-.002165,-.00125,
-.001915,-.001607,
-.001607,-.001915,
-.00125,-.002165,
-.000855,-.002349,
-.000434,-.002462,
0.0,-.0025,
.000434,-.002462,
.000855,-.002349,
.00125,-.002165,
.001607,-.001915,
.001915,-.001607,
.002165,-.00125,
.002349,-.000855,
.002462,-.000434,
.0025,0.0,
45.*
%
%ADD35MACRO35*%
%AMMACRO19*
4,1,36,.0025,0.0,
.002462,.000434,
.002349,.000855,
.002165,.00125,
.001915,.001607,
.001607,.001915,
.00125,.002165,
.000855,.002349,
.000434,.002462,
0.0,.0025,
-.000434,.002462,
-.000855,.002349,
-.00125,.002165,
-.001607,.001915,
-.001915,.001607,
-.002165,.00125,
-.002349,.000855,
-.002462,.000434,
-.0025,0.0,
-.002462,-.000434,
-.002349,-.000855,
-.002165,-.00125,
-.001915,-.001607,
-.001607,-.001915,
-.00125,-.002165,
-.000855,-.002349,
-.000434,-.002462,
0.0,-.0025,
.000434,-.002462,
.000855,-.002349,
.00125,-.002165,
.001607,-.001915,
.001915,-.001607,
.002165,-.00125,
.002349,-.000855,
.002462,-.000434,
.0025,0.0,
90.*
%
%ADD19MACRO19*%
%AMMACRO39*
4,1,36,.003,0.0,
.002954,.000521,
.002819,.001026,
.002598,.0015,
.002298,.001928,
.001928,.002298,
.0015,.002598,
.001026,.002819,
.000521,.002954,
0.0,.003,
-.000521,.002954,
-.001026,.002819,
-.0015,.002598,
-.001928,.002298,
-.002298,.001928,
-.002598,.0015,
-.002819,.001026,
-.002954,.000521,
-.003,0.0,
-.002954,-.000521,
-.002819,-.001026,
-.002598,-.0015,
-.002298,-.001928,
-.001928,-.002298,
-.0015,-.002598,
-.001026,-.002819,
-.000521,-.002954,
0.0,-.003,
.000521,-.002954,
.001026,-.002819,
.0015,-.002598,
.001928,-.002298,
.002298,-.001928,
.002598,-.0015,
.002819,-.001026,
.002954,-.000521,
.003,0.0,
90.*
%
%ADD39MACRO39*%
%AMMACRO18*
4,1,36,.0025,0.0,
.002462,.000434,
.002349,.000855,
.002165,.00125,
.001915,.001607,
.001607,.001915,
.00125,.002165,
.000855,.002349,
.000434,.002462,
0.0,.0025,
-.000434,.002462,
-.000855,.002349,
-.00125,.002165,
-.001607,.001915,
-.001915,.001607,
-.002165,.00125,
-.002349,.000855,
-.002462,.000434,
-.0025,0.0,
-.002462,-.000434,
-.002349,-.000855,
-.002165,-.00125,
-.001915,-.001607,
-.001607,-.001915,
-.00125,-.002165,
-.000855,-.002349,
-.000434,-.002462,
0.0,-.0025,
.000434,-.002462,
.000855,-.002349,
.00125,-.002165,
.001607,-.001915,
.001915,-.001607,
.002165,-.00125,
.002349,-.000855,
.002462,-.000434,
.0025,0.0,
0.0*
%
%ADD18MACRO18*%
%AMMACRO40*
4,1,36,-.003,0.0,
-.002954,.000521,
-.002819,.001026,
-.002598,.0015,
-.002298,.001928,
-.001928,.002298,
-.0015,.002598,
-.001026,.002819,
-.000521,.002954,
0.0,.003,
.000521,.002954,
.001026,.002819,
.0015,.002598,
.001928,.002298,
.002298,.001928,
.002598,.0015,
.002819,.001026,
.002954,.000521,
.003,0.0,
.002954,-.000521,
.002819,-.001026,
.002598,-.0015,
.002298,-.001928,
.001928,-.002298,
.0015,-.002598,
.001026,-.002819,
.000521,-.002954,
0.0,-.003,
-.000521,-.002954,
-.001026,-.002819,
-.0015,-.002598,
-.001928,-.002298,
-.002298,-.001928,
-.002598,-.0015,
-.002819,-.001026,
-.002954,-.000521,
-.003,0.0,
90.*
%
%ADD40MACRO40*%
%AMMACRO13*
4,1,15,.03682,.01914,
.039584,.012455,
.041146,.005393,
.041457,-.001834,
.040509,-.009005,
.03833,-.015903,
.03682,-.01914,
.04197,-.0243,
.045552,-.016643,
.04775,-.00848,
.048497,-.000059,
.047771,.008363,
.045593,.016531,
.042029,.024197,
.04197,.0243,
.03682,.01914,
180.*
4,1,15,.01914,-.03682,
.012455,-.039584,
.005393,-.041146,
-.001834,-.041457,
-.009005,-.040509,
-.015903,-.03833,
-.01914,-.03682,
-.0243,-.04197,
-.016643,-.045552,
-.00848,-.04775,
-.000059,-.048497,
.008363,-.047771,
.016531,-.045593,
.024197,-.042029,
.0243,-.04197,
.01914,-.03682,
180.*
4,1,15,-.03682,-.01914,
-.039584,-.012455,
-.041146,-.005393,
-.041457,.001834,
-.040509,.009005,
-.03833,.015903,
-.03682,.01914,
-.04197,.0243,
-.045552,.016643,
-.04775,.00848,
-.048497,.000059,
-.047771,-.008363,
-.045593,-.016531,
-.042029,-.024197,
-.04197,-.0243,
-.03682,-.01914,
180.*
4,1,15,-.01914,.03682,
-.012455,.039584,
-.005393,.041146,
.001834,.041457,
.009005,.040509,
.015903,.03833,
.01914,.03682,
.0243,.04197,
.016643,.045552,
.00848,.04775,
.000059,.048497,
-.008363,.047771,
-.016531,.045593,
-.024197,.042029,
-.0243,.04197,
-.01914,.03682,
180.*
%
%ADD13MACRO13*%
%AMMACRO12*
4,1,15,-.03682,.01914,
-.039584,.012455,
-.041146,.005393,
-.041457,-.001834,
-.040509,-.009005,
-.03833,-.015903,
-.03682,-.01914,
-.04197,-.0243,
-.045552,-.016643,
-.04775,-.00848,
-.048497,-.000059,
-.047771,.008363,
-.045593,.016531,
-.042029,.024197,
-.04197,.0243,
-.03682,.01914,
180.*
4,1,15,-.01914,-.03682,
-.012455,-.039584,
-.005393,-.041146,
.001834,-.041457,
.009005,-.040509,
.015903,-.03833,
.01914,-.03682,
.0243,-.04197,
.016643,-.045552,
.00848,-.04775,
.000059,-.048497,
-.008363,-.047771,
-.016531,-.045593,
-.024197,-.042029,
-.0243,-.04197,
-.01914,-.03682,
180.*
4,1,15,.03682,-.01914,
.039584,-.012455,
.041146,-.005393,
.041457,.001834,
.040509,.009005,
.03833,.015903,
.03682,.01914,
.04197,.0243,
.045552,.016643,
.04775,.00848,
.048497,.000059,
.047771,-.008363,
.045593,-.016531,
.042029,-.024197,
.04197,-.0243,
.03682,-.01914,
180.*
4,1,15,.01914,.03682,
.012455,.039584,
.005393,.041146,
-.001834,.041457,
-.009005,.040509,
-.015903,.03833,
-.01914,.03682,
-.0243,.04197,
-.016643,.045552,
-.00848,.04775,
-.000059,.048497,
.008363,.047771,
.016531,.045593,
.024197,.042029,
.0243,.04197,
.01914,.03682,
180.*
%
%ADD12MACRO12*%
%ADD42C,.006*%
%ADD46C,.08006*%
%ADD49C,.07306*%
%ADD44C,.06807*%
%ADD45C,.09906*%
%ADD47O,.03004X.06504*%
%ADD48O,.03006X.06506*%
%ADD43C,.16506*%
G75*
%LPD*%
G75*
G36*
G01X-407000Y-793716D02*
X2010999D01*
Y1475775D01*
X-407000D01*
Y-793716D01*
G37*
%LPC*%
G75*
G36*
G01X-15748Y472016D02*
G02X-9874Y466142I0J-5874D01*
G01Y25945D01*
G02X-15748Y20071I-5874J0D01*
G01X-70000D01*
G02X-75874Y25945I0J5874D01*
G01Y466142D01*
G02X-70000Y472016I5874J0D01*
G01X-15748D01*
G37*
G36*
G01X24194Y466518D02*
G03X24144Y466901I-1502J-1D01*
G02X24531Y467404I387J103D01*
G01X38382D01*
Y451968D01*
G03X39366Y448685I5969J0D01*
G03X39346Y448441I1482J-244D01*
G01Y448440D01*
G03X40848Y446938I1502J0D01*
G03X41104Y446960I0J1502D01*
G03X44349Y446000I3246J5009D01*
G01X50257D01*
G03X53760Y447137I-1J5969D01*
G03X54100Y447098I340J1463D01*
G03X55602Y448600I0J1502D01*
G01Y448603D01*
G03X55506Y449130I-1502J-1D01*
G03X56211Y451575I-5251J2838D01*
G01X56216Y451653D01*
X56414Y451841D01*
X56493Y451842D01*
G03X57984Y453344I-11J1502D01*
G01Y456844D01*
G03X56594Y458342I-1502J0D01*
G02X56224Y458741I30J399D01*
G01Y462100D01*
X120508D01*
Y451870D01*
G03X139158Y450055I9413J0D01*
G03X140252Y451500I-407J1445D01*
G03X139673Y452685I-1502J0D01*
G02Y453315I246J315D01*
G03X140252Y454500I-923J1185D01*
G03X139680Y455679I-1501J0D01*
G02X139628Y456258I248J314D01*
G03X140002Y457250I-1129J992D01*
G03X139335Y458499I-1503J0D01*
G01Y462100D01*
X170547D01*
Y451836D01*
G03X169898Y450600I852J-1236D01*
G03X170585Y449338I1503J0D01*
G03X178189Y442456I7604J760D01*
G03X185831Y450098I0J7642D01*
G01Y450245D01*
X185910Y450305D01*
G03X186502Y451500I-910J1195D01*
G03X186132Y452487I-1501J0D01*
G02Y453013I302J263D01*
G03Y454987I-1131J987D01*
G02Y455513I302J263D01*
G03X186502Y456500I-1131J987D01*
G03X185831Y457751I-1502J0D01*
G01Y462100D01*
X250075D01*
Y450886D01*
G03X258504Y442457I8429J0D01*
G01X258505D01*
G03X259916Y442576I0J8429D01*
G03X261100Y441998I1184J924D01*
G03X262602Y443500I0J1502D01*
G01Y443520D01*
G03X266933Y450886I-4098J7366D01*
G01Y462100D01*
X298126D01*
Y451968D01*
G03X304093Y446000I5969J0D01*
G01X310000D01*
G03X315969Y451969I0J5969D01*
G01Y455406D01*
G03Y457648I-1001J1121D01*
G01Y467404D01*
X329803D01*
G02X330190Y466905I-1J-400D01*
G03X330144Y466536I1457J-369D01*
G03X330646Y465415I1503J0D01*
G01Y451968D01*
G03X332616Y447538I5968J1D01*
G03X334112Y446166I1496J130D01*
G03X334738Y446303I-1J1502D01*
G03X336613Y446000I1878J5665D01*
G01X346457D01*
G02X350331Y442126I0J-3874D01*
G01Y438652D01*
G03Y436410I1001J-1121D01*
G01Y418652D01*
G03Y416410I1001J-1121D01*
G01Y398652D01*
G03Y396410I1001J-1121D01*
G01Y378652D01*
G03Y376410I1001J-1121D01*
G01Y358652D01*
G03Y356410I1001J-1121D01*
G01Y339436D01*
G02X349796Y339060I-400J1D01*
G03X349290Y339148I-507J-1414D01*
G03X348169Y338646I0J-1503D01*
G01X345471D01*
G03X339504Y332678I2J-5968D01*
G01Y322834D01*
G03X341102Y318770I5968J1D01*
G03X342604Y317271I1502J3D01*
G01X342606D01*
G03X343103Y317356I-1J1502D01*
G03X345471Y316866I2368J5479D01*
G01X350331D01*
Y301909D01*
G03Y299667I1001J-1121D01*
G01Y281909D01*
G03Y279667I1001J-1121D01*
G01Y271213D01*
X348789Y269671D01*
X267746D01*
G03X265454I-1146J-971D01*
G01X260613D01*
X259345Y270939D01*
Y284227D01*
G03Y285573I-1345J673D01*
G01Y287839D01*
G03X259052Y288546I-999J0D01*
G01X255921Y291677D01*
G03X255214Y291970I-707J-706D01*
G01X224527D01*
G03X222817I-855J-1235D01*
G01X218778D01*
G03X218071Y291677I0J-999D01*
G01X216180Y289786D01*
G03X215887Y289079I706J-707D01*
G01Y258062D01*
X215791Y258003D01*
G03X215607Y257858I523J-852D01*
G01X214095Y256346D01*
X207363Y256340D01*
X207304Y256404D01*
G03X206200Y256887I-1104J-1020D01*
G03X205095Y256402I0J-1501D01*
G01X205035Y256337D01*
X195654Y256328D01*
X195597Y256382D01*
G03X194568Y256790I-1029J-1094D01*
G01X194566D01*
G03X193535Y256380I0J-1502D01*
G01X193478Y256326D01*
X188772Y256322D01*
X188715Y256426D01*
G03X187400Y257202I-1315J-726D01*
G03X186083Y256423I0J-1503D01*
G01X186026Y256319D01*
X180798Y256314D01*
X180744Y256354D01*
G03X179846Y256652I-898J-1204D01*
G03X178945Y256352I0J-1503D01*
G01X178892Y256312D01*
X167300Y256301D01*
Y278886D01*
X171914Y283500D01*
X197500D01*
G03X198207Y283793I0J999D01*
G01X205207Y290793D01*
G03X205500Y291500I-706J707D01*
G01Y299959D01*
G03X206062Y301130I-939J1171D01*
G03X206027Y301452I-1502J0D01*
G01X206022Y301474D01*
X205997Y301583D01*
X211914Y307500D01*
X212858D01*
G03X214362I752J1299D01*
G01X222586D01*
X225793Y304293D01*
G03X226500Y304000I707J706D01*
G01X228747D01*
G03X228800Y303998I83J1499D01*
G03X228853Y304000I-30J1501D01*
G01X236903D01*
X236940Y303847D01*
G03X239860I1460J353D01*
G01X239897Y304000D01*
X244779D01*
G03X247021I1121J1001D01*
G01X247698D01*
G03X248900Y303398I1202J899D01*
G01X248901D01*
G03X249909Y303787I-1J1502D01*
G01X249948Y303823D01*
X250105Y303981D01*
X251793Y302293D01*
G03X252500Y302000I707J706D01*
G01X283000D01*
G03X283707Y302293I0J999D01*
G01X284414Y303000D01*
X305500D01*
G03X306207Y303293I0J999D01*
G01X309707Y306793D01*
G03X310000Y307500I-706J707D01*
G01Y313578D01*
X310118Y313631D01*
G03X311002Y315000I-618J1369D01*
G03X309500Y316502I-1502J0D01*
G01X309499D01*
G03X308665Y316249I0J-1502D01*
G01X307207Y317707D01*
G03X306500Y318000I-707J-706D01*
G01X277683D01*
G03X276660Y318402I-1023J-1101D01*
G03X275691Y318047I1J-1502D01*
G01X275635Y318000D01*
X275500D01*
G03X274793Y317707I0J-999D01*
G01X271086Y314000D01*
X239914D01*
X233707Y320207D01*
G03X233000Y320500I-707J-706D01*
G01X208500D01*
G03X207793Y320207I0J-999D01*
G01X195953Y308367D01*
G03X195031Y308684I-923J-1185D01*
G03X193529Y307182I0J-1502D01*
G03X194827Y305694I1502J0D01*
G01X195000Y305670D01*
Y298914D01*
X191086Y295000D01*
X182377D01*
G03X180011I-1183J-927D01*
G01X165000D01*
G03X164293Y294707I0J-999D01*
G01X162605Y293019D01*
X162493Y293050D01*
G03X162102Y293102I-392J-1450D01*
G01X162100D01*
G03X160598Y291600I0J-1502D01*
G01Y291598D01*
G03X160650Y291207I1502J1D01*
G01X160681Y291095D01*
X123086Y253500D01*
X92682D01*
X92626Y253606D01*
G03X89974I-1326J-706D01*
G01X89918Y253500D01*
X70297D01*
X70260Y253653D01*
G03X68800Y254802I-1460J-353D01*
G03X67568Y254160I0J-1503D01*
G02X66938Y254127I-328J229D01*
G03X65801Y254647I-1137J-983D01*
G03X64381Y253635I0J-1502D01*
G01X64334Y253500D01*
X50000D01*
G03X49293Y253207I0J-999D01*
G01X40446Y244360D01*
X40314Y244436D01*
G03X39567Y244635I-747J-1303D01*
G03X38065Y243133I0J-1502D01*
G01Y243132D01*
G03X38345Y242259I1502J0D01*
G01X38293Y242207D01*
G03X38000Y241500I706J-707D01*
G01Y231768D01*
X34216Y227984D01*
G03X33850Y227100I885J-884D01*
G01Y138900D01*
G03X34216Y138016I1251J0D01*
G01X47841Y124391D01*
X47801Y124273D01*
G03X47721Y123791I1422J-484D01*
G03X49223Y122289I1502J0D01*
G03X49705Y122369I-2J1502D01*
G01X49823Y122409D01*
X50685Y121547D01*
X50670Y121447D01*
G03X50653Y121218I1485J-225D01*
G03X52155Y119716I1502J0D01*
G03X52384Y119733I4J1502D01*
G01X52484Y119748D01*
X53416Y118816D01*
G03X54300Y118450I884J885D01*
G01X60800D01*
Y76200D01*
G03X61093Y75493I999J0D01*
G01X64093Y72493D01*
G03X64800Y72200I707J706D01*
G01X96700D01*
G03X97407Y72493I0J999D01*
G01X98614Y73700D01*
X115021D01*
X115064Y73559D01*
G03X117936I1436J441D01*
G01X117979Y73700D01*
X129379D01*
G03X130500Y73198I1121J1001D01*
G03X132002Y74700I0J1502D01*
G03X131792Y75465I-1502J-1D01*
G01X131713Y75599D01*
X132807Y76693D01*
G03X133100Y77400I-706J707D01*
G01Y104900D01*
G03X132807Y105607I-999J0D01*
G01X127833Y110581D01*
X127902Y110712D01*
G03X128077Y111415I-1327J704D01*
G01Y111416D01*
G03X127500Y112599I-1501J0D01*
G01Y148800D01*
G03X127207Y149507I-999J0D01*
G01X125507Y151207D01*
G03X124800Y151500I-707J-706D01*
G01X120500D01*
Y182086D01*
X125414Y187000D01*
X138094D01*
G03X138165Y186921I778J628D01*
G01X139827Y185259D01*
X139826Y176454D01*
G03X140119Y175747I999J0D01*
G01X143200Y172666D01*
Y170322D01*
G03Y168818I1299J-752D01*
G01Y166714D01*
X140118Y163632D01*
G03X139825Y162925I706J-707D01*
G01X139822Y127135D01*
G03X140115Y126428I999J0D01*
G01X147839Y118704D01*
G03X148546Y118411I707J706D01*
G01X227446D01*
G03X228153Y118704I0J999D01*
G01X234209Y124760D01*
X234332Y124710D01*
G03X234900Y124598I569J1390D01*
G03X236402Y126100I0J1502D01*
G01Y126111D01*
G02X236802Y126514I400J3D01*
G01X244724D01*
G03X246276I776J1286D01*
G01X286920D01*
G03X287627Y126807I0J999D01*
G01X289193Y128373D01*
X289331Y128275D01*
G03X290200Y127998I869J1225D01*
G03X291702Y129500I0J1502D01*
G03X291425Y130369I-1502J0D01*
G01X291327Y130507D01*
X298467Y137647D01*
X330357D01*
X330413Y137541D01*
G03X333069I1328J702D01*
G01X333125Y137647D01*
X348365D01*
X350331Y135681D01*
Y121909D01*
G03Y119667I1001J-1121D01*
G01Y101909D01*
G03Y99667I1001J-1121D01*
G01Y81909D01*
G03Y79667I1001J-1121D01*
G01Y61909D01*
G03Y59667I1001J-1121D01*
G01Y41909D01*
G03Y39667I1001J-1121D01*
G01Y21909D01*
G03Y19667I1001J-1121D01*
G01Y7874D01*
G02X346457Y4000I-3874J0D01*
G01X343339D01*
G03X341097I-1121J-1001D01*
G01X323339D01*
G03X321097I-1121J-1001D01*
G01X303339D01*
G03X301097I-1121J-1001D01*
G01X283339D01*
G03X281097I-1121J-1001D01*
G01X263339D01*
G03X261097I-1121J-1001D01*
G01X243339D01*
G03X241097I-1121J-1001D01*
G01X223339D01*
G03X221097I-1121J-1001D01*
G01X203339D01*
G03X201097I-1121J-1001D01*
G01X183339D01*
G03X181097I-1121J-1001D01*
G01X163339D01*
G03X161097I-1121J-1001D01*
G01X143339D01*
G03X141097I-1121J-1001D01*
G01X123339D01*
G03X121097I-1121J-1001D01*
G01X103339D01*
G03X101097I-1121J-1001D01*
G01X83339D01*
G03X81097I-1121J-1001D01*
G01X63339D01*
G03X61097I-1121J-1001D01*
G01X43339D01*
G03X41097I-1121J-1001D01*
G01X23339D01*
G03X21097I-1121J-1001D01*
G01X7874D01*
G02X4029Y7400I0J3874D01*
G03X4502Y8494I-1029J1094D01*
G03X4000Y9615I-1503J0D01*
G01Y27373D01*
G03Y29615I-1001J1121D01*
G01Y47373D01*
G03Y49615I-1001J1121D01*
G01Y67373D01*
G03Y69615I-1001J1121D01*
G01Y87373D01*
G03Y89615I-1001J1121D01*
G01Y107373D01*
G03Y109615I-1001J1121D01*
G01Y127373D01*
G03Y129615I-1001J1121D01*
G01Y147373D01*
G03Y149615I-1001J1121D01*
G01Y167373D01*
G03Y169615I-1001J1121D01*
G01Y187373D01*
G03Y189615I-1001J1121D01*
G01Y207373D01*
G03Y209615I-1001J1121D01*
G01Y227373D01*
G03Y229615I-1001J1121D01*
G01Y247373D01*
G03Y249615I-1001J1121D01*
G01Y267373D01*
G03Y269615I-1001J1121D01*
G01Y287373D01*
G03Y289615I-1001J1121D01*
G01Y307373D01*
G03Y309615I-1001J1121D01*
G01Y316866D01*
X8858D01*
G03X14827Y322835I0J5969D01*
G01Y324189D01*
G03Y326431I-1001J1121D01*
G01Y332677D01*
G03X8858Y338646I-5969J0D01*
G01X4000D01*
Y341005D01*
G03Y343247I-1001J1121D01*
G01Y361005D01*
G03Y363247I-1001J1121D01*
G01Y381005D01*
G03Y383247I-1001J1121D01*
G01Y401005D01*
G03Y403247I-1001J1121D01*
G01Y421005D01*
G03Y423247I-1001J1121D01*
G01Y441005D01*
G03X4502Y442126I-1001J1121D01*
G03X4129Y443117I-1503J0D01*
G02X7874Y446000I3745J-991D01*
G01X17718D01*
G03X19600Y446305I-2J5968D01*
G03X20224Y446169I625J1366D01*
G01X20225D01*
G03X21722Y447543I0J1503D01*
G03X23685Y451968I-4006J4425D01*
G01Y465391D01*
G03X24194Y466518I-993J1127D01*
G37*
G36*
G01X53354Y229750D02*
X59750D01*
Y201403D01*
X59591Y201370D01*
G03Y198430I309J-1470D01*
G01X59750Y198397D01*
Y172056D01*
G03X60116Y171172I1251J0D01*
G01X67772Y163516D01*
G03X68656Y163150I884J885D01*
G01X84782D01*
X89950Y157982D01*
Y149618D01*
X67121Y126789D01*
X67028Y126797D01*
G03X66900Y126802I-123J-1497D01*
G03X65398Y125300I0J-1502D01*
G03X65403Y125172I1502J-5D01*
G01X65411Y125079D01*
X61779Y121447D01*
G02X61170Y121499I-283J283D01*
G03X59945Y122132I-1225J-869D01*
G03X58515Y121089I0J-1502D01*
G01X58470Y120950D01*
X54818D01*
X36350Y139418D01*
Y216646D01*
G03Y219354I-650J1354D01*
G01Y226582D01*
X39518Y229750D01*
X50646D01*
G03X53354I1354J650D01*
G37*
G36*
G01X208914Y318500D02*
X232586D01*
X238793Y312293D01*
G03X239500Y312000I707J706D01*
G01X256392D01*
X256422Y311835D01*
G03X259378I1478J264D01*
G01X259408Y312000D01*
X271500D01*
G03X272207Y312293I0J999D01*
G01X275678Y315764D01*
G03X276660Y315398I983J1136D01*
G03X277862Y316000I0J1501D01*
G01X306086D01*
X308000Y314086D01*
Y307914D01*
X305086Y305000D01*
X284000D01*
G03X283293Y304707I0J-999D01*
G01X282586Y304000D01*
X252914D01*
X251207Y305707D01*
G03X250500Y306000I-707J-706D01*
G01X249923D01*
G03X247877I-1023J-1101D01*
G01X247021D01*
G03X244779I-1121J-1001D01*
G01X230222D01*
X230169Y306118D01*
G03X227431I-1369J-618D01*
G01X227378Y306000D01*
X226914D01*
X223707Y309207D01*
G03X223000Y309500I-707J-706D01*
G01X214939D01*
G03X212281I-1329J-700D01*
G01X211500D01*
G03X210793Y309207I0J-999D01*
G01X204166Y302580D01*
X204119Y302566D01*
G03X203058Y301130I441J-1436D01*
G03X203500Y300066I1502J0D01*
G01Y291914D01*
X197086Y285500D01*
X171500D01*
G03X170793Y285207I0J-999D01*
G01X165593Y280007D01*
G03X165300Y279300I706J-707D01*
G01Y256885D01*
G02X164924Y256485I-400J-1D01*
G03X163511Y254986I89J-1499D01*
G03X163790Y254114I1502J0D01*
G03X163700Y253700I910J-415D01*
G03Y253693I1000J-3D01*
G01X163737Y247969D01*
X158998Y243229D01*
X124322D01*
X124272Y243355D01*
G03X121480I-1396J-555D01*
G01X121430Y243229D01*
X118934D01*
G03X116746I-1094J-1029D01*
G01X72229D01*
G03X71522Y242936I0J-999D01*
G01X71474Y242888D01*
G03X70900Y243002I-574J-1388D01*
G03X69398Y241500I0J-1502D01*
G03X69471Y241039I1502J2D01*
G01X69508Y240922D01*
X60836Y232250D01*
X40000D01*
Y241086D01*
X50414Y251500D01*
X90755D01*
X90788Y251488D01*
G03X91812I512J1411D01*
G01X91845Y251500D01*
X117593D01*
X117615Y251325D01*
G03X119105Y250009I1490J186D01*
G03X120595Y251325I0J1502D01*
G01X120617Y251500D01*
X123500D01*
G03X124207Y251793I0J999D01*
G01X149230Y276816D01*
X149368Y276717D01*
G03X150240Y276438I872J1223D01*
G03X151742Y277940I0J1502D01*
G03X151463Y278812I-1502J0D01*
G01X151364Y278950D01*
X162595Y290181D01*
X162635Y290197D01*
G03X163503Y291065I-535J1403D01*
G01X163519Y291105D01*
X165414Y293000D01*
X180144D01*
G03X182244I1050J1074D01*
G01X191500D01*
G03X192207Y293293I0J999D01*
G01X196707Y297793D01*
G03X197000Y298500I-706J707D01*
G01Y306586D01*
X208914Y318500D01*
G37*
G36*
G01X238162Y185244D02*
X237312Y184394D01*
X217486D01*
X216667Y185213D01*
Y206318D01*
G03X216374Y207025I-999J0D01*
G01X214057Y209342D01*
X214130Y209474D01*
G03X214293Y210104I-1139J631D01*
G03X212991Y211406I-1302J0D01*
G03X211711Y210344I0J-1302D01*
G01X211680Y210181D01*
X211153D01*
X211122Y210344D01*
G03X208562I-1280J-240D01*
G01X208531Y210181D01*
X204853D01*
X204822Y210344D01*
G03X202262I-1280J-240D01*
G01X202231Y210181D01*
X201704D01*
X201673Y210344D01*
G03X199113I-1280J-240D01*
G01X199082Y210181D01*
X192255D01*
X192224Y210344D01*
G03X189664I-1280J-240D01*
G01X189633Y210181D01*
X189105D01*
X189074Y210344D01*
G03X186514I-1280J-240D01*
G01X186483Y210181D01*
X185956D01*
X185925Y210344D01*
G03X183365I-1280J-240D01*
G01X183334Y210181D01*
X179657D01*
X179626Y210344D01*
G03X177066I-1280J-240D01*
G01X177035Y210181D01*
X176507D01*
X176476Y210344D01*
G03X175196Y211406I-1280J-240D01*
G03X173896Y210168I0J-1302D01*
G03X173352Y209888I164J-986D01*
G01X173168Y209704D01*
X173053Y209738D01*
G03X172621Y209802I-434J-1438D01*
G03X171119Y208300I0J-1502D01*
G03X171224Y207749I1502J1D01*
G03X171013Y207135I788J-614D01*
G01Y203342D01*
X169732Y202061D01*
X166660D01*
G03X164102I-1279J-786D01*
G01X155578D01*
X154983Y202656D01*
Y211891D01*
G03X154690Y212598I-999J0D01*
G01X152197Y215091D01*
G03X151720Y215357I-707J-707D01*
G01X151230Y215473D01*
G03X151000Y215500I-231J-973D01*
G01X143500D01*
G03X142810Y215223I1J-1000D01*
G01X140139Y212674D01*
G03X139829Y211951I690J-724D01*
G01X139828Y200473D01*
X139778Y200416D01*
G03Y198426I1125J-995D01*
G01X139828Y198370D01*
Y197450D01*
X139827Y195915D01*
Y193651D01*
X139768Y193592D01*
G03X139328Y192530I1062J-1062D01*
G01Y192529D01*
G03X139827Y191411I1502J0D01*
G01Y190854D01*
X137973Y189000D01*
X125000D01*
G03X124293Y188707I0J-999D01*
G01X118793Y183207D01*
G03X118500Y182500I706J-707D01*
G01Y151500D01*
X116400D01*
G03X115693Y151207I0J-999D01*
G01X108407Y143921D01*
G03X108114Y143214I706J-707D01*
G01Y140133D01*
X107956Y140099D01*
G03Y137161I314J-1469D01*
G01X108114Y137127D01*
Y129728D01*
X97493Y119107D01*
G03X97200Y118400I706J-707D01*
G01Y76771D01*
G03X96498Y75500I800J-1271D01*
G01Y75499D01*
G03X96751Y74665I1502J0D01*
G01X96286Y74200D01*
X65214D01*
X62800Y76614D01*
Y118932D01*
X92084Y148216D01*
G03X92450Y149100I-885J884D01*
G01Y158500D01*
G03X92084Y159384I-1251J0D01*
G01X86184Y165284D01*
G03X85300Y165650I-884J-885D01*
G01X69174D01*
X62250Y172574D01*
Y230836D01*
X71569Y240155D01*
X71596Y240169D01*
G03X72231Y240804I-696J1331D01*
G01X72245Y240831D01*
X72643Y241229D01*
X80115D01*
X80157Y241084D01*
G03X83043I1443J416D01*
G01X83085Y241229D01*
X116694D01*
G03X118986I1146J971D01*
G01X159412D01*
G03X160119Y241522I0J999D01*
G01X165447Y246850D01*
G03X165740Y247557I-706J707D01*
G03Y247564I-1000J4D01*
G01X165703Y253263D01*
X166720Y254300D01*
X172954Y254306D01*
X173005Y254180D01*
G03X174400Y253234I1395J556D01*
G03X175796Y254183I0J1501D01*
G01X175846Y254309D01*
X177570Y254310D01*
X178596Y254311D01*
X178656Y254233D01*
G03X179846Y253648I1190J918D01*
G03X181038Y254236I0J1502D01*
G01X181098Y254314D01*
X181633D01*
X182451Y254315D01*
X186807Y254319D01*
X186843Y254305D01*
G03X187400Y254198I557J1396D01*
G01X187401D01*
G03X187961Y254307I-2J1502D01*
G01X187995Y254321D01*
X193410Y254326D01*
X193470Y254262D01*
G03X194567Y253786I1097J1026D01*
G03X195666Y254264I0J1502D01*
G01X195725Y254328D01*
X195960D01*
X205121Y254337D01*
X205179Y254284D01*
G03X206200Y253883I1022J1101D01*
G03X207223Y254286I-1J1502D01*
G01X207281Y254339D01*
X215410Y254347D01*
X215899D01*
X215950Y254312D01*
G03X216800Y254048I850J1238D01*
G03X217650Y254312I0J1502D01*
G01X217701Y254347D01*
X218000D01*
G03X218126Y254339I126J992D01*
G03X218252Y254347I0J1000D01*
G01X222362D01*
X222413Y254224D01*
G03X225187I1387J576D01*
G01X225238Y254347D01*
X229302D01*
X229386Y254329D01*
G03X229999Y254198I614J1371D01*
G01X230001D01*
G03X230615Y254329I0J1502D01*
G01X230654Y254347D01*
X241529D01*
G03X243851I1161J953D01*
G01X251712D01*
X251767Y254237D01*
G03X254453I1343J672D01*
G01X254508Y254347D01*
X257062D01*
X257116Y254232D01*
G03X259834I1359J640D01*
G01X259888Y254347D01*
X267639D01*
X270600Y251386D01*
Y228800D01*
G03X270893Y228093I999J0D01*
G01X274893Y224093D01*
G03X275600Y223800I707J706D01*
G01X311186D01*
X312600Y222386D01*
Y216814D01*
X310903Y215117D01*
X310847Y215104D01*
G03X310588Y215017I315J-1366D01*
G01X310549Y215000D01*
X309596D01*
G03X307324I-1136J-822D01*
G01X295814D01*
X294707Y216107D01*
G03X294000Y216400I-707J-706D01*
G01X241400D01*
G03X240693Y216107I0J-999D01*
G01X238455Y213869D01*
G03X238162Y213162I706J-707D01*
G01Y185244D01*
G37*
G36*
G01X116814Y149500D02*
X124386D01*
X125500Y148386D01*
Y112465D01*
G03X125073Y111416I1075J-1049D01*
G03X125510Y110357I1502J0D01*
G03X125793Y109793I989J143D01*
G01X131100Y104486D01*
Y82723D01*
X130967Y82675D01*
G03Y79845I503J-1415D01*
G01X131100Y79797D01*
Y77814D01*
X128986Y75700D01*
X119997D01*
X119960Y75853D01*
G03X117040I-1460J-353D01*
G01X117003Y75700D01*
X99497D01*
X99460Y75853D01*
G03X99200Y76403I-1460J-354D01*
G01Y117986D01*
X108422Y127208D01*
X108549Y127146D01*
G03X109200Y126998I650J1354D01*
G03X110702Y128500I0J1502D01*
G03X110114Y129692I-1502J0D01*
G01Y134619D01*
X110238Y134670D01*
G03Y137450I-567J1390D01*
G01X110114Y137501D01*
Y142800D01*
X116814Y149500D01*
G37*
G36*
G01X350331Y201909D02*
G03Y199667I1001J-1121D01*
G01Y181909D01*
G03Y179667I1001J-1121D01*
G01Y161909D01*
G03Y159667I1001J-1121D01*
G01Y141909D01*
G03X349829Y140793I1000J-1121D01*
G01Y140711D01*
X348765Y139647D01*
X332276D01*
X332243Y139659D01*
G03X331741Y139745I-501J-1416D01*
G03X331239Y139659I-1J-1502D01*
G01X331206Y139647D01*
X298053D01*
G03X297346Y139354I0J-999D01*
G01X286506Y128514D01*
X246821D01*
G03X244179I-1321J-713D01*
G01X235549D01*
G03X234842Y128221I0J-999D01*
G01X227032Y120411D01*
X148960D01*
X141822Y127549D01*
X141825Y161504D01*
Y161505D01*
G03Y161518I-1000J6D01*
G01Y162511D01*
X144907Y165593D01*
G03X145200Y166300I-706J707D01*
G01Y168241D01*
G03Y170899I-700J1329D01*
G01Y173080D01*
G03X144907Y173787I-999J0D01*
G01X141826Y176868D01*
X141827Y191404D01*
X141887Y191462D01*
G03X142332Y192529I-1057J1067D01*
G01Y192530D01*
G03X141887Y193597I-1502J0D01*
G01X141827Y193656D01*
X141828Y198234D01*
X141896Y198294D01*
G03Y200548I-993J1127D01*
G01X141828Y200608D01*
X141829Y211523D01*
X143901Y213500D01*
X150001D01*
G02X150400Y213121I0J-400D01*
G03X151900Y211698I1500J79D01*
G03X152474Y211812I0J1502D01*
G01X152597Y211863D01*
X152983Y211477D01*
Y202242D01*
G03X153276Y201535I999J0D01*
G01X154457Y200354D01*
G03X155164Y200061I707J706D01*
G01X164495D01*
G03X166267I886J1214D01*
G01X170146D01*
G03X170853Y200354I0J999D01*
G01X172720Y202221D01*
G03X173013Y202928I-706J707D01*
G01Y206721D01*
X173210Y206918D01*
X173243Y206933D01*
G03X173988Y207678I-622J1367D01*
G01X174003Y207711D01*
X174473Y208181D01*
X212390D01*
X214667Y205904D01*
Y184799D01*
G03X214960Y184092I999J0D01*
G01X216365Y182687D01*
G03X217072Y182394I707J706D01*
G01X237726D01*
G03X238433Y182687I0J999D01*
G01X239869Y184123D01*
G03X240162Y184830I-706J707D01*
G01Y212748D01*
X241814Y214400D01*
X259883D01*
X259925Y214257D01*
G03X261269Y213255I1344J400D01*
G03X262189Y213599I0J1402D01*
G02X262468Y213583I131J-151D01*
G03X263580Y213090I1113J1010D01*
G01X267080D01*
G03X268163Y213552I-1J1503D01*
G02X268443Y213560I144J-139D01*
G03X269391Y213191I948J1033D01*
G03X270750Y214249I0J1402D01*
G01X270788Y214400D01*
X293586D01*
X294693Y213293D01*
G03X295400Y213000I707J706D01*
G01X307700D01*
G03X308460Y212776I760J1177D01*
G03X309175Y212972I0J1402D01*
G01X309222Y213000D01*
X309965D01*
G03X311158Y212335I1193J738D01*
G03X312560Y213737I0J1402D01*
G03X312556Y213843I-1402J0D01*
G01X312549Y213935D01*
X314307Y215693D01*
G03X314600Y216400I-706J707D01*
G01Y222800D01*
G03X314307Y223507I-999J0D01*
G01X312307Y225507D01*
G03X311600Y225800I-707J-706D01*
G01X276014D01*
X272600Y229214D01*
Y249521D01*
X272741Y249564D01*
G03X273802Y251000I-441J1436D01*
G03X272386Y252500I-1502J0D01*
G01X272310Y252504D01*
X268760Y256054D01*
G03X268053Y256347I-707J-706D01*
G01X258759D01*
X258741Y256350D01*
G03X258475Y256374I-267J-1478D01*
G03X258209Y256350I1J-1502D01*
G01X258191Y256347D01*
X253545D01*
X253518Y256355D01*
G03X253110Y256411I-406J-1446D01*
G03X252702Y256355I-2J-1502D01*
G01X252675Y256347D01*
X243767D01*
G03X241613I-1077J-1047D01*
G01X231356D01*
G03X228644I-1356J-648D01*
G01X219351D01*
G03X219329Y256369I-718J-696D01*
G01X217887Y257811D01*
Y262542D01*
X218018Y262590D01*
G03Y265410I-518J1410D01*
G01X217887Y265458D01*
Y288665D01*
X219192Y289970D01*
X222379D01*
G03X224965I1293J766D01*
G01X254800D01*
X257345Y287425D01*
Y286252D01*
G03Y283548I656J-1352D01*
G01Y270525D01*
G03X257638Y269818I999J0D01*
G01X259492Y267964D01*
G03X260199Y267671I707J706D01*
G01X265506D01*
G03X267694I1094J1029D01*
G01X348777D01*
X350331Y266117D01*
Y261909D01*
G03Y259667I1001J-1121D01*
G01Y241909D01*
G03Y239667I1001J-1121D01*
G01Y221909D01*
G03Y219667I1001J-1121D01*
G01Y201909D01*
G37*
G36*
G01X364205Y466142D02*
G02X370079Y472016I5874J0D01*
G01X476378D01*
G02X482252Y466142I0J-5874D01*
G01Y-509842D01*
G02X476378Y-515716I-5874J0D01*
G01X370079D01*
G02X364205Y-509842I0J5874D01*
G01Y466142D01*
G37*
%LPD*%
G75*
G36*
G01X95870Y443980D02*
G02Y446986I0J1503D01*
G01X99370D01*
G02Y443980I0J-1503D01*
G01X95870D01*
G37*
G36*
G01X246488Y104290D02*
G02Y107294I0J1502D01*
G01X249988D01*
G02Y104290I0J-1502D01*
G01X246488D01*
G37*
G36*
G01X255213Y104596D02*
G02Y107602I0J1503D01*
G01X258713D01*
G02Y104596I0J-1503D01*
G01X255213D01*
G37*
G36*
G01X52750Y422698D02*
G02Y425702I0J1502D01*
G01X56250D01*
G02Y422698I0J-1502D01*
G01X52750D01*
G37*
G36*
G01X81990Y446582D02*
G02Y449588I0J1503D01*
G01X85490D01*
G02Y446582I0J-1503D01*
G01X81990D01*
G37*
G36*
G01X221225Y411652D02*
G02Y408648I0J-1502D01*
G01X217725D01*
G02Y411652I0J1502D01*
G01X221225D01*
G37*
G36*
G01X169347Y94778D02*
G02Y97784I0J1503D01*
G01X172847D01*
G02Y94778I0J-1503D01*
G01X169347D01*
G37*
G36*
G01X159923D02*
G02Y97784I0J1503D01*
G01X163423D01*
G02Y94778I0J-1503D01*
G01X159923D01*
G37*
G36*
G01X216725Y443722D02*
G02Y440718I0J-1502D01*
G01X213225D01*
G02Y443722I0J1502D01*
G01X216725D01*
G37*
G36*
G01X182350Y387136D02*
G02Y384132I0J-1502D01*
G01X178850D01*
G02Y387136I0J1502D01*
G01X182350D01*
G37*
G36*
G01X60622Y429770D02*
G02Y432776I0J1503D01*
G01X64122D01*
G02Y429770I0J-1503D01*
G01X60622D01*
G37*
G36*
G01X92801Y451290D02*
G02Y454296I0J1503D01*
G01X96301D01*
G02Y451290I0J-1503D01*
G01X92801D01*
G37*
G36*
G01X72150Y422696D02*
G02Y425702I0J1503D01*
G01X75650D01*
G02Y422696I0J-1503D01*
G01X72150D01*
G37*
G36*
G01X162550Y388836D02*
G02Y385832I0J-1502D01*
G01X159050D01*
G02Y388836I0J1502D01*
G01X162550D01*
G37*
G36*
G01X176859Y55780D02*
G02Y61386I0J2803D01*
G01X184733D01*
G02Y55780I0J-2803D01*
G01X176859D01*
G37*
G36*
G01X165048Y49874D02*
G02Y55480I0J2803D01*
G01X172922D01*
G02Y49874I0J-2803D01*
G01X165048D01*
G37*
G36*
G01X153237Y55780D02*
G02Y61386I0J2803D01*
G01X161111D01*
G02Y55780I0J-2803D01*
G01X153237D01*
G37*
G36*
G01X242870Y239000D02*
G02X243872Y238580I0J-1405D01*
G02Y236612I-853J-984D01*
G02X242870Y236192I-1002J985D01*
G02X242378Y236281I0J1404D01*
G01X242344Y236294D01*
X240395D01*
G02X239870Y236192I-525J1302D01*
G02Y239000I0J1404D01*
G02X240395Y238898I0J-1404D01*
G01X242344D01*
X242378Y238911D01*
G02X242870Y239000I492J-1315D01*
G37*
G36*
G01X239998Y225853D02*
Y229002D01*
G02X242602I1302J0D01*
G01Y226194D01*
G02X242638Y225890I-1264J-304D01*
G02X242261Y224974I-1301J0D01*
G02X241300Y224551I-961J880D01*
G02X239998Y225853I0J1302D01*
G37*
G36*
G01X250749Y236604D02*
X253898D01*
G02Y233998I0J-1303D01*
G01X250749D01*
G02Y236604I0J1303D01*
G37*
G36*
G01X253898Y233454D02*
X257047D01*
G02Y230848I0J-1303D01*
G01X253898D01*
G02Y233454I0J1303D01*
G37*
G36*
G01X244450D02*
X247599D01*
G02Y230848I0J-1303D01*
G01X244450D01*
G02Y233454I0J1303D01*
G37*
G36*
G01X250749Y230304D02*
X253898D01*
G02Y227700I0J-1302D01*
G01X250749D01*
G02Y230304I0J1302D01*
G37*
G36*
G01X92320Y213343D02*
G02X105315Y226338I12995J0D01*
G01X105316D01*
G02X118310Y213343I-1J-12995D01*
G02X110107Y201264I-12995J0D01*
G03X110093Y200526I147J-372D01*
G02X117130Y189721I-4777J-10805D01*
G01Y183421D01*
G02X93500I-11815J0D01*
G01Y189721D01*
G02X100538Y200527I11815J0D01*
G03X100523Y201264I-162J365D01*
G02X92320Y213343I4792J12079D01*
G37*
G36*
G01X267722Y178294D02*
G02Y175288I0J-1503D01*
G01X264222D01*
G02Y178294I0J1503D01*
G01X267722D01*
G37*
G36*
G01X266080Y208764D02*
G02Y205760I0J-1502D01*
G01X262580D01*
G02Y208764I0J1502D01*
G01X266080D01*
G37*
G36*
G01X375904Y-439648D02*
G02Y-436642I0J1503D01*
G01X379304D01*
G02Y-439648I0J-1503D01*
G01X375904D01*
G37*
G36*
G01X375964Y-217462D02*
G02Y-214456I0J1503D01*
G01X379364D01*
G02Y-217462I0J-1503D01*
G01X375964D01*
G37*
G36*
G01X375876Y-161376D02*
G02Y-158370I0J1503D01*
G01X379276D01*
G02Y-161376I0J-1503D01*
G01X375876D01*
G37*
G36*
G01X397080Y-122524D02*
G02Y-119518I0J1503D01*
G01X400480D01*
G02Y-122524I0J-1503D01*
G01X397080D01*
G37*
G36*
G01X375964Y10810D02*
G02Y13816I0J1503D01*
G01X379364D01*
G02Y10810I0J-1503D01*
G01X375964D01*
G37*
G36*
G01X375904Y66896D02*
G02Y69902I0J1503D01*
G01X379304D01*
G02Y66896I0J-1503D01*
G01X375904D01*
G37*
G36*
G01X375964Y380082D02*
G02Y383088I0J1503D01*
G01X379364D01*
G02Y380082I0J-1503D01*
G01X375964D01*
G37*
G36*
G01X396992Y-465710D02*
G02Y-462704I0J1503D01*
G01X400392D01*
G02Y-465710I0J-1503D01*
G01X396992D01*
G37*
G54D46*
X65945Y297776D03*
G54D49*
X403692Y-481375D03*
X393692D03*
Y-456375D03*
X403692D03*
X382604Y-455313D03*
X372604D03*
Y-430313D03*
X382604D03*
X382664Y373753D03*
X372664D03*
Y398753D03*
X382664D03*
X393750Y272050D03*
X403750D03*
Y247050D03*
X393750D03*
Y200538D03*
X403750D03*
Y225538D03*
X393750D03*
X393780Y-128853D03*
X403780D03*
Y-103853D03*
X393780D03*
X403750Y-57222D03*
X393750D03*
Y-82222D03*
X403750D03*
X372604Y76231D03*
X382604D03*
Y51231D03*
X372604D03*
X413750Y-57222D03*
Y-82222D03*
X382664Y4481D03*
X372664D03*
Y29481D03*
X382664D03*
X403750Y398810D03*
X413750D03*
Y423810D03*
X403750D03*
X413750Y200538D03*
Y225538D03*
Y272050D03*
Y247050D03*
X372664Y-223791D03*
X382664D03*
Y-198791D03*
X372664D03*
X393750Y398810D03*
Y423810D03*
X372576Y-152041D03*
X382576D03*
Y-177041D03*
X372576D03*
G54D44*
X45276Y18465D03*
X17716D03*
X336615D03*
X309055D03*
X291733Y20040D03*
X264173D03*
G54D45*
X144685Y297776D03*
G54D47*
X102190Y64975D03*
G54D48*
X63569Y455094D03*
G54D43*
X-58189Y454331D03*
X27300Y68200D03*
X340639Y432809D03*
X464567Y-498031D03*
Y454331D03*
G54D14*
X3000Y8494D03*
Y28494D03*
Y48494D03*
Y68494D03*
Y88494D03*
Y108494D03*
Y128494D03*
Y148494D03*
Y168494D03*
Y188494D03*
Y208494D03*
Y228494D03*
Y248494D03*
Y268494D03*
Y288494D03*
Y308494D03*
Y342126D03*
Y362126D03*
Y382126D03*
Y402126D03*
Y422126D03*
Y442126D03*
X9407Y10554D03*
X12900Y105500D03*
X12500Y102000D03*
X16626Y195848D03*
X19129D03*
Y193048D03*
X16626D03*
X19100Y187420D03*
X19129Y204248D03*
X17000Y208017D03*
Y211541D03*
X16626Y198648D03*
Y201448D03*
X19129Y198648D03*
Y201448D03*
X16626Y204248D03*
X17000Y215713D03*
Y219288D03*
X15922Y224568D03*
Y227168D03*
X18422Y224568D03*
Y227168D03*
X18000Y240900D03*
Y237900D03*
Y249900D03*
Y246900D03*
Y243900D03*
X17065Y255712D03*
X15688Y259063D03*
X6200Y312900D03*
X8300Y314700D03*
X13827Y325310D03*
X13869Y352239D03*
X14000Y401700D03*
Y406700D03*
Y404200D03*
X14600Y422500D03*
X14700Y425000D03*
X22218Y3000D03*
X27323Y25842D03*
X23723Y123791D03*
Y120791D03*
X32223Y123791D03*
Y120791D03*
X31890Y110400D03*
X23736Y127758D03*
Y130758D03*
X32236Y127758D03*
Y130758D03*
X31920Y186610D03*
X21250Y206220D03*
X21000Y227000D03*
Y224500D03*
X21135Y236587D03*
X21205Y232767D03*
X21135Y240667D03*
Y243737D03*
X24690Y246467D03*
Y251967D03*
X21135Y246837D03*
X21035Y249937D03*
X24690Y249267D03*
X24705Y258767D03*
X22237Y311481D03*
Y308592D03*
X30638Y311957D03*
Y309068D03*
X33000Y318700D03*
X25811Y319400D03*
X32000Y326300D03*
X23535Y329990D03*
X23810Y322534D03*
X31300Y329900D03*
X31000Y342500D03*
X34300Y375000D03*
X26300Y374400D03*
X36200Y368400D03*
X31600Y379600D03*
X33100Y392100D03*
X32700Y395381D03*
X25202Y425329D03*
X29400Y430900D03*
X23677Y422419D03*
X31500Y428500D03*
X32100Y432800D03*
X20225Y447671D03*
X22692Y466518D03*
X42218Y3000D03*
X35044Y35751D03*
X43926Y62248D03*
X45500Y92500D03*
X45276Y98488D03*
X40340Y100710D03*
X45001Y95144D03*
X40723Y123791D03*
Y120791D03*
X49223Y123791D03*
Y121291D03*
X38300Y109200D03*
X40940Y112559D03*
X40736Y127758D03*
Y130758D03*
X49236Y127758D03*
Y130758D03*
X47294Y184491D03*
X36599Y189016D03*
X37360Y194050D03*
X37823Y198346D03*
X48035Y191535D03*
X39408Y195990D03*
X47714Y212227D03*
X48940Y204871D03*
X47948Y201000D03*
X39900Y211000D03*
X48059Y214825D03*
X48023Y217860D03*
X39800Y213800D03*
X35700Y218000D03*
X39567Y243133D03*
X40500Y236900D03*
X35600Y241200D03*
Y238200D03*
X41574Y255937D03*
X37485Y258807D03*
X41100Y248900D03*
X46220Y277170D03*
X47440Y308691D03*
X39039Y309044D03*
Y311933D03*
X47440Y312080D03*
X50950Y318050D03*
X43500Y317100D03*
X48420Y321616D03*
X44525Y324000D03*
X39100Y321600D03*
X44481Y328760D03*
X38560Y329739D03*
X35500Y340500D03*
Y335000D03*
X44220Y341008D03*
X44500Y344000D03*
Y355500D03*
X37400Y359900D03*
X44500Y348000D03*
X44525Y360000D03*
X35100Y352400D03*
X44500Y351600D03*
X38200Y364855D03*
X35900Y363025D03*
X37800Y371225D03*
X44525Y364000D03*
Y368000D03*
X37300Y375000D03*
X44525Y376000D03*
X37735Y391200D03*
X44525Y391650D03*
X35101Y381610D03*
X44525Y384000D03*
X37020Y385600D03*
X47075Y391730D03*
X44500Y380000D03*
X44525Y394150D03*
X36911Y394915D03*
X37067Y398337D03*
X44341Y406480D03*
X44330Y401450D03*
X36600Y408600D03*
X39530Y409100D03*
X42900Y412900D03*
X46100Y412700D03*
X43600Y422800D03*
X42200Y435900D03*
X38000Y428800D03*
X48050Y436350D03*
X45100Y435800D03*
X46100Y422800D03*
X40848Y448440D03*
X62218Y3000D03*
X54200Y25400D03*
X53000Y41500D03*
X53600Y44100D03*
X56348Y36210D03*
X59425Y53075D03*
X50508Y57459D03*
X50710Y54724D03*
X57500Y75500D03*
X60000D03*
X55000Y76000D03*
X63086Y65762D03*
X52120Y78373D03*
X59240Y67242D03*
X52502Y80978D03*
X53400Y102788D03*
X52155Y121218D03*
X60112Y113992D03*
X53267Y109094D03*
X59945Y117795D03*
Y120630D03*
X60411Y130200D03*
X52237Y129522D03*
X60800Y137000D03*
X61123Y133070D03*
X52876Y195712D03*
X52410Y186900D03*
X59700Y196200D03*
X52410Y190190D03*
X57141Y209341D03*
X59900Y199900D03*
X64050Y201010D03*
X52948Y200700D03*
X58000Y217700D03*
X58823Y213531D03*
X52000Y230400D03*
X63300Y237600D03*
X51600Y241200D03*
X59850Y235830D03*
X51010Y233570D03*
X49700Y242900D03*
X50700Y250400D03*
X62500Y272500D03*
X61200Y282600D03*
X58654Y290605D03*
X58900Y288075D03*
X54660Y311660D03*
X60561Y314843D03*
X60613Y312012D03*
X60600Y318000D03*
X64230Y303210D03*
X56600Y324300D03*
X52800Y322400D03*
X63000Y324100D03*
X56600Y318000D03*
X52820Y325200D03*
X60225Y336099D03*
X57400Y345400D03*
X58035Y370100D03*
X54400Y374700D03*
X55294Y369729D03*
X52475Y364000D03*
X52765Y390200D03*
X59500Y394000D03*
X58620Y408779D03*
X63200Y408600D03*
X52330Y413350D03*
X59097Y433502D03*
X57470Y426544D03*
X51535D03*
X59511Y424477D03*
X60622Y431273D03*
X64122D03*
X56250Y424200D03*
X52750D03*
X56482Y450344D03*
X62600Y450700D03*
X54100Y448600D03*
X56500Y447600D03*
X63563Y460100D03*
X56476D03*
X56482Y456844D03*
Y453344D03*
X63569Y456844D03*
Y453344D03*
X76500Y66500D03*
X65928Y76500D03*
X75280Y75704D03*
X72500Y66500D03*
X66830Y122329D03*
X66900Y125300D03*
X72044Y132312D03*
X71970Y135893D03*
X69195Y135799D03*
X69285Y132321D03*
X67126Y128100D03*
X66874Y130590D03*
X68335Y141369D03*
X68375Y144100D03*
X68434Y149506D03*
X68432Y152147D03*
X70580Y167179D03*
X72300Y159400D03*
X68600Y159160D03*
X76442Y166907D03*
X73550Y166680D03*
X67330Y169267D03*
X68960Y173300D03*
X75284Y180800D03*
X71124Y178565D03*
X65301Y187762D03*
X67486Y186414D03*
X75300Y183875D03*
X71146Y186489D03*
X71370Y188993D03*
X67386Y191935D03*
X67486Y188977D03*
X74046Y186490D03*
X71600Y200900D03*
X72150Y204810D03*
X76670Y208772D03*
X75000Y214000D03*
X72500D03*
X70453Y222900D03*
X74583Y217314D03*
X72000Y235925D03*
X70900Y241500D03*
X71100Y233575D03*
X67700Y229725D03*
X65801Y253145D03*
X77010Y256645D03*
X65755Y256045D03*
X76200Y247400D03*
X73011Y246365D03*
X77384Y253769D03*
X68800Y253300D03*
X65800Y260875D03*
X76500Y270700D03*
X74000Y270800D03*
X68990Y260465D03*
X77437Y262760D03*
X76284Y280470D03*
X78600Y283970D03*
X75960Y284049D03*
X65100Y282475D03*
X75870Y290700D03*
X78770Y290708D03*
X75300Y305150D03*
X69500Y308700D03*
X64567Y306665D03*
X73400Y313700D03*
X77500Y316100D03*
X73000Y323400D03*
X68500Y325100D03*
X81000Y321900D03*
X76900Y323000D03*
X76500Y325500D03*
X78700Y340000D03*
X78900Y336600D03*
X71700Y340600D03*
X67900Y400525D03*
X79000Y395500D03*
X73976Y408665D03*
X69057Y419700D03*
X77860Y408678D03*
X77592Y413437D03*
X69139Y413452D03*
X66319Y413492D03*
X74782Y413800D03*
X67000Y408800D03*
X69700D03*
X78800Y423800D03*
X66297Y433002D03*
X71035Y426543D03*
X76770D03*
X69030Y422653D03*
X71200Y431700D03*
X72150Y424199D03*
X75650D03*
X77600Y431400D03*
X79010Y445750D03*
X72800Y437900D03*
X70650Y460100D03*
X77500D03*
X82218Y3000D03*
X91700Y66500D03*
X86500Y75000D03*
X88000Y66500D03*
X84500D03*
X90151Y68985D03*
X86700Y119100D03*
X92500Y116200D03*
X88500Y128000D03*
X89256Y135056D03*
X89170Y141540D03*
X89200Y138800D03*
X81500Y176515D03*
X81800Y188500D03*
X80788Y190812D03*
X82370Y197010D03*
X90900Y222850D03*
X81600Y241500D03*
X87500Y237300D03*
X91300Y252900D03*
X80300Y243700D03*
X80270Y247830D03*
X84000Y261375D03*
X83500Y266900D03*
X84016Y258230D03*
X91500Y267000D03*
X85672Y283985D03*
X92300Y282100D03*
X81864Y297900D03*
X85600Y298100D03*
X90923Y293520D03*
X82200Y308700D03*
X82022Y303350D03*
X84126Y311790D03*
X79600Y312000D03*
X85500Y323400D03*
Y326700D03*
X92698Y323224D03*
X93288Y330289D03*
X85600Y335000D03*
X81900Y337100D03*
X81700Y342600D03*
X86300Y397600D03*
X89487Y408435D03*
X87800Y410300D03*
X84801Y409760D03*
X92500Y408630D03*
X86481Y407871D03*
X96030Y409400D03*
X81552Y409660D03*
X84320Y430510D03*
X93259Y424200D03*
X88565Y426535D03*
X79600Y426400D03*
X92001Y450402D03*
X82256Y445577D03*
X85276Y445550D03*
X81990Y448085D03*
X85490D03*
X92870Y437831D03*
X89700Y437900D03*
X84823Y460100D03*
X91909Y458275D03*
X92801Y452793D03*
X102218Y3000D03*
X107000Y44500D03*
X104575Y62369D03*
X102190Y63225D03*
X104600Y50501D03*
X104575Y67581D03*
X95400Y66500D03*
X98000Y75500D03*
X102190Y66725D03*
X111000Y77000D03*
X104500Y73500D03*
X107124Y71004D03*
X104425Y82500D03*
X110950Y82050D03*
X106000Y91900D03*
X108727Y99153D03*
X100000Y98500D03*
X111075Y104600D03*
X105916Y109952D03*
X100360Y116500D03*
X101230Y127010D03*
X96400Y137475D03*
X102999Y131799D03*
X108270Y138630D03*
X95950Y152900D03*
X95944Y149687D03*
X103500Y240619D03*
X98720Y236980D03*
X103580Y237400D03*
X106600Y253689D03*
X95300Y247100D03*
X107200Y265000D03*
X106800Y262076D03*
X97440Y283590D03*
X106574Y280028D03*
X106100Y282900D03*
X100700Y293600D03*
X108551Y294241D03*
X99990Y311200D03*
X105000Y311900D03*
X99990Y307900D03*
X105100Y309300D03*
X94400Y311100D03*
Y307200D03*
X100500Y328547D03*
X96457Y323194D03*
X103000Y323800D03*
X95060Y327625D03*
X106852Y323292D03*
X97800Y325700D03*
X97608Y335534D03*
X99026Y338368D03*
X103180Y336286D03*
X108108Y395100D03*
X103400Y420000D03*
X95280Y412500D03*
X105500Y418200D03*
X100457Y409100D03*
X108701Y418300D03*
X98300Y407600D03*
X108336Y411547D03*
X108500Y408680D03*
X109048Y425853D03*
X104112Y422946D03*
X103461Y425875D03*
X95845Y424755D03*
X97156Y450437D03*
X94560Y443287D03*
X100225Y443127D03*
X106700Y447730D03*
X95770Y437920D03*
X95870Y445483D03*
X99370D03*
X103900Y447640D03*
X98996Y458275D03*
X106083D03*
X96301Y452793D03*
X122218Y3000D03*
X111000Y44600D03*
X115000Y44500D03*
X125800Y47330D03*
X122500Y58000D03*
X112800Y60400D03*
X112600Y52800D03*
X118500Y75500D03*
X116500Y74000D03*
X109121Y69500D03*
X116560Y88651D03*
X123710Y82300D03*
X123740Y79791D03*
X120726Y105000D03*
X115200Y98200D03*
X123325Y111000D03*
X120724Y108937D03*
X120626Y123500D03*
X112000D03*
X116200Y115100D03*
X109350Y115501D03*
X109200Y118500D03*
X120500Y115525D03*
X109200Y128500D03*
X118990Y131580D03*
X109670Y136060D03*
X118692Y137304D03*
X113000Y160700D03*
Y158000D03*
X122156Y157844D03*
X122900Y170100D03*
X123120Y213088D03*
X119060Y199695D03*
X123790Y227656D03*
X113590Y245170D03*
X118300Y237500D03*
X123690Y230156D03*
X122876Y242800D03*
X117840Y242200D03*
X121200Y234890D03*
X112200Y234520D03*
X116143Y230790D03*
X112900Y239200D03*
X122876Y245300D03*
X120020Y254430D03*
X119105Y251511D03*
X121720Y265330D03*
X109800Y264928D03*
X111600Y262730D03*
Y284000D03*
X120070Y273700D03*
X115000D03*
X111177Y293471D03*
X122957Y300991D03*
X123100Y295974D03*
X120600Y293471D03*
X110565Y296331D03*
X118009Y313810D03*
Y311200D03*
X124935Y324900D03*
X115535Y335235D03*
X124300Y348800D03*
X115600Y337900D03*
X114700Y351200D03*
X121200Y359200D03*
X111330Y357800D03*
X120200Y361600D03*
X114700Y348500D03*
X111460Y361770D03*
X115000Y369500D03*
X111950Y371200D03*
X122047Y372260D03*
X125650Y368650D03*
X122330Y364670D03*
X111869Y365454D03*
X119200Y389700D03*
X117410Y381350D03*
X110900Y378500D03*
X123100Y390600D03*
X122600Y394600D03*
X119026Y393332D03*
X112800Y421600D03*
X113000Y416200D03*
X116632Y411500D03*
X122498Y419675D03*
X112796Y412490D03*
X119500Y433600D03*
X111510Y434710D03*
X121700Y424005D03*
X123170Y433200D03*
X127900Y45000D03*
X129575Y57375D03*
X133000Y59900D03*
X140730Y72600D03*
X130500Y74700D03*
X129300Y82650D03*
X131470Y81260D03*
X129500Y91475D03*
X129328Y122500D03*
X126575Y111416D03*
X131528Y114271D03*
X135500Y138000D03*
Y135000D03*
X134400Y127652D03*
X131700Y131000D03*
X133500Y146800D03*
X138458Y146458D03*
X133500Y149385D03*
X124500Y167100D03*
X132500Y167300D03*
X126500Y158000D03*
X133690Y158100D03*
X136190D03*
X126300Y176575D03*
X137900Y179160D03*
X135300Y175100D03*
X125700Y183700D03*
X129810Y191310D03*
X135000Y206900D03*
X124338Y204742D03*
X124779Y201633D03*
X126153Y199079D03*
X135000Y221200D03*
X132500Y221900D03*
X138100Y213600D03*
X134891Y225171D03*
X124226Y225194D03*
X134358Y230069D03*
X130167Y234733D03*
X138000Y244600D03*
X128900Y255898D03*
X127600Y259700D03*
X131216Y280187D03*
X128760Y273701D03*
X137083Y278045D03*
X137196Y274491D03*
X132420Y273811D03*
X138600Y295900D03*
X124016Y313784D03*
X135462Y313727D03*
X124100Y311100D03*
X136100Y334000D03*
X129800Y325800D03*
X125900Y337600D03*
X133300Y334100D03*
X136000Y341000D03*
X133100Y358900D03*
X132600Y350090D03*
X124350Y352450D03*
X129776Y374500D03*
X138700Y376600D03*
X133640Y390524D03*
X126340Y382700D03*
X125174Y393916D03*
X124287Y406262D03*
X127300Y392600D03*
X135300Y399900D03*
X137900Y399500D03*
X131540Y394690D03*
X132700Y402700D03*
X129900Y415583D03*
X133500Y409110D03*
X129135Y410250D03*
X133070Y420874D03*
X134300Y416414D03*
X128866Y433066D03*
X135350Y433016D03*
X124500Y424005D03*
X132070Y433110D03*
X133572Y423935D03*
X125930Y433110D03*
X138750Y451500D03*
X138500Y457250D03*
X138750Y454500D03*
X142218Y3000D03*
X147947Y9800D03*
X146800Y79000D03*
X152800Y75600D03*
X140869Y89055D03*
X145000Y90700D03*
X145100Y87400D03*
X142400Y91300D03*
X141100Y86500D03*
X141700Y96929D03*
X140869Y104803D03*
Y120551D03*
Y112677D03*
X147600Y117000D03*
X151800Y116500D03*
X152800Y111600D03*
X149800Y138100D03*
Y135100D03*
X145185Y134214D03*
X142892Y136645D03*
X142000Y146000D03*
X143269Y150456D03*
X150155Y145086D03*
X152556Y147683D03*
X148429Y147682D03*
X148400Y155765D03*
X144500Y169570D03*
X146300Y161010D03*
X153134Y178572D03*
X153200Y170990D03*
X146882Y177501D03*
X150619Y178646D03*
X145296Y188835D03*
X140830Y192530D03*
X153051Y187354D03*
X150005Y184973D03*
X149100Y189963D03*
X144280Y195130D03*
X151900Y213200D03*
X143980Y199674D03*
X147800Y200789D03*
X140903Y199421D03*
X143742Y203395D03*
X152500Y199500D03*
X146390Y224040D03*
X146000Y216350D03*
X141954Y224274D03*
X142300Y216300D03*
X145500Y227700D03*
X142702Y227817D03*
X153100Y234800D03*
X149862Y243788D03*
X142085Y230549D03*
X151040Y237870D03*
X145250Y256890D03*
X145580Y248082D03*
X141280Y256310D03*
X142780Y266830D03*
X149215Y267745D03*
X152400Y284400D03*
X150240Y277940D03*
X152400Y293400D03*
X150293Y302117D03*
X147500Y289405D03*
X141890Y310570D03*
X150293Y315493D03*
X142500Y345800D03*
X142300Y336700D03*
X144800D03*
X144700Y334100D03*
X153419Y341978D03*
X141045Y355309D03*
X150900Y360325D03*
X151695Y357900D03*
X149500Y356700D03*
X141000Y358500D03*
X140700Y370252D03*
X145703Y370700D03*
X139200Y372510D03*
X149000Y383070D03*
X152100Y378400D03*
X152500Y382600D03*
X150820Y387325D03*
X143300Y396400D03*
X140300Y395100D03*
X139400Y392460D03*
X151265Y399500D03*
X142511Y393690D03*
X146600Y410600D03*
X153079Y412000D03*
X143000Y414600D03*
X140600Y412300D03*
X152100Y425700D03*
X145365Y426050D03*
X148060Y423500D03*
X152200Y423100D03*
X148041Y426700D03*
X138987Y423935D03*
X151398Y449930D03*
X149041Y458750D03*
X162218Y3000D03*
X165700Y11100D03*
X166719Y75874D03*
X158246Y78872D03*
X156710Y73420D03*
X168297Y93976D03*
X164429Y93991D03*
X158873Y93976D03*
X166500Y96400D03*
X163423Y96281D03*
X159923D03*
X166200Y105500D03*
X158420Y116610D03*
X159700Y112000D03*
X156286Y124903D03*
X156200Y111600D03*
X162657Y117297D03*
X154050Y137100D03*
X159000Y135000D03*
X166700Y132360D03*
X156406Y129203D03*
X162419Y131032D03*
X166733Y128700D03*
X155325Y139440D03*
X153954Y145086D03*
X161900Y150500D03*
X165690Y149622D03*
X159328Y160847D03*
X156481Y155933D03*
X162200Y158200D03*
X159900Y155600D03*
X161240Y177820D03*
X161237Y181735D03*
Y185815D03*
X161240Y190477D03*
X166361Y209794D03*
X162594Y212585D03*
Y210085D03*
X166140Y205955D03*
X165381Y201274D03*
X166308Y225189D03*
X153744Y217435D03*
X153800Y214900D03*
X162653Y218843D03*
X159643Y226484D03*
X162200Y221376D03*
X163500Y229184D03*
X167200Y222600D03*
X155800Y234700D03*
X161200Y233600D03*
X165500Y236100D03*
X157200Y240000D03*
X156970Y255000D03*
X165013Y254986D03*
X160973D03*
X164500Y266000D03*
X163690Y268610D03*
X160590Y263300D03*
X156970Y263250D03*
X164800Y263300D03*
X158750Y284949D03*
X168392Y298493D03*
X160850Y301344D03*
X168300Y301100D03*
X162100Y291600D03*
X161400Y307600D03*
X170800Y317600D03*
X164500Y314800D03*
X155000Y321100D03*
X164790Y341100D03*
X158459Y340898D03*
X158467Y344067D03*
X163800Y356800D03*
X161154Y376704D03*
X156300Y376300D03*
X164318Y389102D03*
X157282D03*
X156900Y385700D03*
X154500Y387350D03*
X159050Y387334D03*
X162550D03*
X165500Y386000D03*
X165501Y382800D03*
X158200Y381400D03*
X155452Y401000D03*
X154000Y414750D03*
X160540Y416912D03*
X162100Y414000D03*
X165194Y428688D03*
X156101Y425100D03*
X167008Y430718D03*
X165500Y433100D03*
X167865Y427771D03*
X163700Y422119D03*
X159396Y449408D03*
X160700Y445550D03*
X158100Y442700D03*
X160852Y460118D03*
X168029Y456660D03*
X157500Y453390D03*
X182218Y3000D03*
X176900Y14625D03*
X178200Y76145D03*
X175700Y76245D03*
X173853Y93991D03*
X182925Y84300D03*
X179900Y91300D03*
X169700Y102250D03*
X176300Y98700D03*
X172847Y96281D03*
X169347D03*
X180333Y114292D03*
X182000Y117200D03*
X171600Y114000D03*
X182865Y113706D03*
X174600Y114000D03*
X169100Y113900D03*
X182103Y132294D03*
X182108Y129094D03*
X170867Y128211D03*
X178290Y128824D03*
X174553Y128728D03*
X176550Y125210D03*
X178284Y132394D03*
X170610Y131900D03*
X174436Y132394D03*
X168800Y126800D03*
X172100Y146300D03*
X176000Y140500D03*
X172890Y153260D03*
X171700Y156900D03*
X169500Y180200D03*
X170800Y193100D03*
X172621Y208300D03*
X173800Y225400D03*
X170400Y214700D03*
X172400Y220700D03*
X175300Y240000D03*
X174400Y249136D03*
Y254736D03*
X179846Y255150D03*
X180458Y258825D03*
X174400Y251936D03*
X174292Y263300D03*
X171592Y263312D03*
X168710Y272256D03*
X172977Y277000D03*
X182435Y281797D03*
X179217Y278528D03*
X168656Y275156D03*
X181194Y294074D03*
X182232Y296424D03*
X173880Y312430D03*
X174232Y304333D03*
X176563Y310917D03*
X176533Y314049D03*
X170550Y304050D03*
X169077Y308677D03*
X170561Y306631D03*
X182372Y325961D03*
X181050Y332250D03*
X171098Y341224D03*
X182700Y342216D03*
X169200Y349400D03*
X180350Y368650D03*
X177500Y369100D03*
X177082Y387402D03*
X178850Y385634D03*
X182350D03*
X169669Y399419D03*
X172550Y398690D03*
X172530Y420950D03*
X182750Y426750D03*
X184480Y429370D03*
X171400Y450600D03*
X193100Y69100D03*
X189400Y69600D03*
X187272Y84472D03*
X191312Y84512D03*
X190200Y100500D03*
X198281Y101286D03*
X187700Y99000D03*
X187400Y101500D03*
X186891Y113991D03*
X190744Y114456D03*
X187069Y116800D03*
X184729Y115820D03*
X187360Y132425D03*
X187435Y129623D03*
X195983Y132294D03*
X191482Y129294D03*
X195983D03*
X186200Y125600D03*
X184000Y140500D03*
X196577Y141185D03*
X189700Y140400D03*
X196827Y240349D03*
X191693Y236370D03*
X185897Y249936D03*
X193084Y257400D03*
X194567Y255288D03*
X187400Y255700D03*
X191583Y261363D03*
X193386Y269142D03*
X184200Y264900D03*
X185000Y270700D03*
X189228Y280655D03*
X183625Y273500D03*
X196200Y278200D03*
X196100Y281820D03*
X192380Y291900D03*
X196443Y294065D03*
X191199Y300200D03*
X185725Y307320D03*
X195031Y307182D03*
X194600Y313300D03*
X197853Y307200D03*
X197155Y314223D03*
X188546Y326356D03*
X190465Y344426D03*
X190600Y337900D03*
X183800Y345400D03*
X197775Y346617D03*
X194800Y341700D03*
X191408Y357451D03*
X197450Y356560D03*
X190922Y350990D03*
X191420Y354710D03*
X190965Y348090D03*
X197711Y349250D03*
X195000Y373900D03*
X187400Y379400D03*
X197400Y367600D03*
Y370250D03*
X184118Y387402D03*
X197620Y385425D03*
X187300Y384300D03*
X197660Y390870D03*
X190050Y389140D03*
X190100Y392270D03*
X191843Y403995D03*
X189054Y397500D03*
X194500Y402600D03*
X195800Y396780D03*
X200274Y410960D03*
X185875Y415051D03*
X185245Y417500D03*
X190370Y422490D03*
X195000Y422540D03*
X199940Y423700D03*
X197600Y415400D03*
X190270Y409962D03*
X195300Y432327D03*
X189766Y432050D03*
X189838Y434910D03*
X186720Y432490D03*
X186300Y448700D03*
X185000Y451500D03*
X189600Y459800D03*
X185000Y454000D03*
Y456500D03*
X191780Y453300D03*
Y456700D03*
X202218Y3000D03*
X207700Y59100D03*
X211400Y59238D03*
X204300Y60600D03*
X201500Y61000D03*
X209142Y53664D03*
X213100Y69300D03*
X204100Y67400D03*
X209500Y92326D03*
X211800Y93870D03*
X209824Y106122D03*
X203600Y117000D03*
X208200Y111760D03*
X203970Y125500D03*
X199985Y132294D03*
X212757Y127064D03*
X212727Y129654D03*
X208627Y132394D03*
X208576Y128957D03*
X204120Y132294D03*
X200000Y128764D03*
X208500Y126057D03*
X212727Y132154D03*
X211200Y140513D03*
X211490Y143700D03*
X205598Y140480D03*
X203542Y213254D03*
X206200Y255385D03*
X198990Y247811D03*
X200680Y257540D03*
X206051Y247911D03*
X211265Y267300D03*
X201100Y265120D03*
X214034Y261482D03*
X201000Y262500D03*
X203090Y269229D03*
X205590Y269129D03*
X205900Y266130D03*
X205130Y282000D03*
X204207Y278200D03*
X204258Y286691D03*
X213258Y273265D03*
X207220Y301180D03*
X204560Y301130D03*
X212911Y293869D03*
X206430Y298780D03*
X199729Y314565D03*
X208628Y324665D03*
X200300Y328800D03*
X207750Y366500D03*
X208000Y373240D03*
X208360Y384890D03*
X208565Y404501D03*
X200222Y398150D03*
X213200Y399166D03*
X199880Y402846D03*
X203180Y416371D03*
X207539Y408686D03*
X200000Y407040D03*
X205223Y422665D03*
X207278Y416022D03*
X206150Y412821D03*
X202513Y434800D03*
X198405D03*
X211865Y444520D03*
X199000Y444500D03*
X205200Y445400D03*
X213225Y442220D03*
X200000Y455800D03*
X209300Y457700D03*
X222218Y3000D03*
X214306Y62233D03*
X229900Y61000D03*
X227547Y74275D03*
X219600Y74000D03*
X215800Y69300D03*
X218600D03*
X224000Y74275D03*
X218600Y92100D03*
X221300D03*
X224330Y83210D03*
X227760Y82524D03*
X224958Y107236D03*
X219900Y101300D03*
X216400Y106400D03*
X226040Y101220D03*
X222890Y101240D03*
X226887Y117297D03*
X223300Y117400D03*
X221500Y125100D03*
X217262Y129294D03*
X225284Y132294D03*
X229342Y129240D03*
X221278Y129294D03*
X225284D03*
X217262Y132294D03*
X221278D03*
X225300Y125200D03*
X227700Y151900D03*
X221000Y243000D03*
X220100Y237200D03*
X223800Y254800D03*
X227316Y256700D03*
X215100Y244100D03*
X215500Y247111D03*
X216800Y255550D03*
X215510Y253310D03*
X225275Y246000D03*
X217500Y264000D03*
X230196Y267477D03*
X219900Y267100D03*
X220866Y272160D03*
X227232Y270539D03*
X226405Y266335D03*
X222833Y261668D03*
X225441Y282267D03*
X227841Y275773D03*
X219339Y284138D03*
X219359Y281580D03*
X226500Y273000D03*
X229220Y283250D03*
X223672Y290735D03*
X223646Y293960D03*
X215600Y316800D03*
X213610Y308800D03*
X216384Y312216D03*
X228800Y312100D03*
X226100Y325065D03*
X217300Y322800D03*
X225650Y337520D03*
X221000Y343800D03*
X216405Y335970D03*
X214175Y333740D03*
X228230Y340040D03*
X221000Y352000D03*
X223160Y362600D03*
X213490Y373690D03*
X226710Y364815D03*
X223420Y367080D03*
X222575Y387625D03*
X227206Y400100D03*
X217390Y401340D03*
X222986Y400323D03*
X220134Y400780D03*
X222225Y407650D03*
X216725D03*
X217725Y410150D03*
X221225D03*
X226830Y435170D03*
X225000Y433100D03*
X219250Y422150D03*
X213900Y436000D03*
X217100Y436100D03*
X218085Y444520D03*
X224000Y449100D03*
X216725Y442220D03*
X222200Y458700D03*
X215000Y458600D03*
X242218Y3000D03*
X233000Y47100D03*
X237000Y47200D03*
X230800Y57613D03*
X240000Y67400D03*
X239347Y79457D03*
X239660Y91920D03*
X232150Y82480D03*
X235630Y104990D03*
X231592Y110500D03*
X237280Y107510D03*
X229000Y101000D03*
X232325Y101230D03*
X236648Y100739D03*
X242812Y117501D03*
X234500Y117500D03*
X230293Y117417D03*
X239900Y117550D03*
X239206Y112300D03*
X242800Y132200D03*
X231100Y125600D03*
X233511Y132594D03*
X234900Y126100D03*
X229396Y132294D03*
X233511Y129594D03*
X242500Y129000D03*
X242195Y141003D03*
X232384Y148884D03*
X230535Y244564D03*
X237700Y257387D03*
X237730Y248085D03*
X242690Y255300D03*
X230000Y255700D03*
X232773Y269532D03*
X232300Y261200D03*
X239298Y268800D03*
X242940Y268500D03*
X233033Y266483D03*
X229630Y264404D03*
X242087Y271427D03*
X238531Y263081D03*
X231900Y272700D03*
X241188Y279347D03*
X241263Y282654D03*
X234500Y293500D03*
X242700Y306800D03*
X228800Y302700D03*
X236688Y311217D03*
X238400Y304200D03*
X228800Y305500D03*
X235400Y303800D03*
X241400Y328100D03*
X242592Y330683D03*
X243010Y323400D03*
X230445Y325945D03*
X233468Y341046D03*
X235000Y335300D03*
X231689Y334896D03*
X233500Y346911D03*
Y343911D03*
X233300Y356890D03*
X231500Y352500D03*
X233650Y359628D03*
X233800Y354300D03*
X233600Y371500D03*
X230287Y373100D03*
X233800Y390118D03*
X228230Y390390D03*
X232470Y382280D03*
X233600Y377300D03*
X233790Y384490D03*
X236670Y394550D03*
X241231Y407285D03*
X236860Y407300D03*
X229900Y436600D03*
X236900Y440565D03*
X239500Y447750D03*
X235400Y451600D03*
X231250Y447000D03*
X235200Y449100D03*
X231400Y449500D03*
X241436Y445784D03*
X240200Y450650D03*
X228200Y459100D03*
X236221Y454400D03*
X240010Y456000D03*
X240210Y453400D03*
X231400Y452000D03*
X248359Y46559D03*
X249475Y55812D03*
X256000Y56000D03*
X248700Y75900D03*
X255750Y77350D03*
X253000Y77500D03*
X250000Y73000D03*
X250900Y90900D03*
X257800Y82800D03*
X256900Y87300D03*
X251200Y93800D03*
X254397Y103697D03*
X244987Y103528D03*
X251113Y102919D03*
X252300Y107664D03*
X245391Y99589D03*
X251900Y100100D03*
X255213Y106099D03*
X249988Y105792D03*
X246488D03*
X244208Y97302D03*
X247200Y117400D03*
X253100Y119900D03*
X245310Y113910D03*
X252374Y132159D03*
X245500Y127800D03*
X245520Y130600D03*
X258500Y146400D03*
X251354Y152877D03*
X249300Y237600D03*
X247689Y247929D03*
X253110Y254909D03*
X253100Y257800D03*
X252639Y247885D03*
X256700Y263800D03*
X255700Y260000D03*
X247470Y269990D03*
X253388Y273655D03*
X250288Y273581D03*
X251459Y286542D03*
Y283542D03*
X257145Y279700D03*
X246200Y299700D03*
X246514Y294325D03*
Y296825D03*
X258100Y295080D03*
X254355Y300577D03*
X247923Y316400D03*
X245900Y305000D03*
X257900Y312100D03*
X248900Y304900D03*
X247923Y319000D03*
X253320Y323327D03*
X256124Y336355D03*
X243700Y372730D03*
X244790Y375910D03*
X243410Y381323D03*
X248800Y385700D03*
X249400Y410300D03*
X252350Y412850D03*
X257810Y435100D03*
X245300Y445800D03*
X246700Y451500D03*
X246500Y448500D03*
X243375Y448375D03*
X246700Y454100D03*
X262218Y3000D03*
X267022Y12166D03*
X269095Y34625D03*
X260970Y42441D03*
X259000Y47500D03*
X267939Y41122D03*
X268500Y45500D03*
X268675Y74400D03*
X267168Y93768D03*
X260132D03*
X259894Y90072D03*
X263102Y91725D03*
X272505Y83545D03*
X260050Y87026D03*
X259759Y103651D03*
X259500Y101100D03*
X265801Y106040D03*
X260970Y98600D03*
X258713Y106099D03*
X264989Y101732D03*
X268435Y121476D03*
X269561Y130987D03*
X271300Y132900D03*
X269493Y138604D03*
X260200Y132395D03*
X260388Y125001D03*
X263294Y153366D03*
X263030Y150846D03*
X268442Y153299D03*
X265942D03*
Y150799D03*
X268442D03*
X269004Y144450D03*
Y141950D03*
X269133Y164982D03*
X265226D03*
X268339Y222126D03*
X272300Y251000D03*
X258628Y247600D03*
X258475Y254872D03*
X267100Y265000D03*
X269016Y266991D03*
X259500Y263700D03*
X262730Y267600D03*
X258000Y266300D03*
X266600Y268700D03*
X262700Y265100D03*
X258000Y284900D03*
X262100Y280700D03*
X266200Y300500D03*
Y294800D03*
X261500Y290440D03*
X266300Y307500D03*
X262310Y311225D03*
X264265Y315817D03*
X262930Y325300D03*
X261300Y334100D03*
X259420Y345930D03*
Y343230D03*
Y340630D03*
X265922Y354238D03*
X273580Y354250D03*
X271990Y362360D03*
X272100Y396300D03*
X274190Y408900D03*
X265100Y395100D03*
X272400Y392400D03*
X269700Y411379D03*
X271500Y418300D03*
X265100Y424000D03*
X266300Y435900D03*
X267100Y432900D03*
X263800Y430300D03*
X272999Y430500D03*
X271500Y446800D03*
X271710Y449840D03*
X266727Y443185D03*
X261700Y439700D03*
X265130Y440070D03*
X261100Y443500D03*
X269534Y459061D03*
X269561Y456044D03*
X282218Y3000D03*
X277000Y41982D03*
X286000Y47000D03*
X282440Y51941D03*
X274219Y51641D03*
X279934Y51688D03*
X286000Y67975D03*
X279800Y72700D03*
X274400Y90019D03*
X290000Y82000D03*
X273400Y92800D03*
X276400Y92300D03*
X287578Y84092D03*
X283500Y89500D03*
X277505Y83545D03*
X282505D03*
X278300Y95019D03*
X274760Y105140D03*
X275386Y102710D03*
X280910Y102880D03*
X279200Y114100D03*
X288116Y120306D03*
X285250Y117250D03*
X274200Y109500D03*
X280400Y126000D03*
X274500Y131629D03*
X279600Y131400D03*
X275960Y126010D03*
X273450Y125050D03*
X287796Y131542D03*
X288280Y126212D03*
X280744Y142070D03*
X283248Y142046D03*
X280616Y150971D03*
X283616D03*
X285899Y153542D03*
X283399D03*
X278155Y176085D03*
X286000Y242100D03*
X279983Y235254D03*
X282483D03*
X283974Y251372D03*
X286800Y251400D03*
X276200Y251500D03*
X280082Y251328D03*
X280030Y267098D03*
Y264098D03*
X284357Y267027D03*
Y264027D03*
X287755Y287538D03*
X281889Y287636D03*
X282911Y279569D03*
X285911D03*
X287507Y301596D03*
X281300Y308800D03*
X287050Y305850D03*
X289939Y309060D03*
X276660Y316900D03*
X276155Y329999D03*
X273355Y330001D03*
X286372Y320700D03*
X289600Y322253D03*
X286372Y326768D03*
X285860Y336131D03*
X277500Y348469D03*
X275520Y357910D03*
X277290Y355820D03*
X277572Y351198D03*
X276100Y375900D03*
X287725Y363473D03*
X276145Y366455D03*
X276400Y370400D03*
X276100Y381500D03*
X284614Y387136D03*
X283664Y379236D03*
X273100Y381500D03*
X283973Y382553D03*
X285191Y390840D03*
X287630Y389378D03*
X277700Y406100D03*
X287476Y396680D03*
X281300Y419300D03*
X278200Y408700D03*
X278900Y421400D03*
X281300Y416200D03*
X277700Y412580D03*
X287500Y416100D03*
X278409Y433722D03*
X276400Y431810D03*
X275100Y427682D03*
X274619Y424725D03*
X283622Y447155D03*
X275138Y451215D03*
X276632Y439502D03*
X283674Y449975D03*
X277563Y460028D03*
X283707Y459398D03*
X283715Y452769D03*
X302218Y3000D03*
X300600Y10591D03*
X288856Y12166D03*
X295402Y48051D03*
X290245Y46978D03*
X297466Y51521D03*
X297575Y73738D03*
X293773Y73530D03*
X300856Y104059D03*
X301151Y108649D03*
X294600Y106900D03*
X298575Y101900D03*
X304000Y116500D03*
X294800Y111800D03*
X298975Y118900D03*
X301000Y121016D03*
X300500Y125000D03*
X295075Y119100D03*
X301936Y135797D03*
X294200Y128800D03*
X301000Y129900D03*
X290200Y129500D03*
X293693Y152232D03*
X290889Y152318D03*
X298005Y151118D03*
Y148618D03*
Y146118D03*
X301507Y195435D03*
X301120Y226421D03*
Y229810D03*
X290586Y234844D03*
X288086D03*
X299138Y244513D03*
X302687Y275497D03*
X291500Y287670D03*
Y285170D03*
X298840Y279640D03*
X291000Y297700D03*
X291300Y315900D03*
X296938Y325700D03*
X301500Y326500D03*
X290120Y339370D03*
X290000Y335600D03*
X300700Y341300D03*
X296780Y371500D03*
X298748Y390118D03*
X298152Y393332D03*
X297399Y397382D03*
X292700Y403700D03*
X290800Y438300D03*
X291623Y447747D03*
X291703Y450819D03*
X291689Y453912D03*
Y456912D03*
Y459912D03*
X295729Y453912D03*
Y456912D03*
Y459912D03*
X297738Y452418D03*
Y458418D03*
Y455418D03*
X313977Y33400D03*
X303575Y54516D03*
X315100Y116400D03*
X307400Y122300D03*
X304436Y135897D03*
X307500Y125635D03*
X313800Y124300D03*
X307560Y128500D03*
X309521Y226397D03*
X317110Y219140D03*
X309521Y229786D03*
X307500Y256500D03*
X305000Y252400D03*
X307600Y252300D03*
X307800Y259200D03*
X312114Y288439D03*
X312272Y282107D03*
X302800Y286200D03*
X311670Y285160D03*
X302879Y282487D03*
Y279686D03*
X309700Y294789D03*
X315810Y293450D03*
X312315Y293207D03*
X317430Y295665D03*
X314820Y296128D03*
X314201Y302361D03*
X314180Y299440D03*
X303077Y297519D03*
X314132Y310178D03*
X314170Y307020D03*
X309500Y315000D03*
X304000Y305000D03*
X311000Y320500D03*
X312300Y340700D03*
X315075Y366500D03*
X314340Y373296D03*
X311925Y366475D03*
X312226Y382766D03*
X308500Y382100D03*
X314985Y397639D03*
Y394639D03*
X308926Y401900D03*
X314969Y456527D03*
X322218Y3000D03*
X319175Y60200D03*
X321800Y60055D03*
X322600Y76100D03*
X322500Y102900D03*
X331881Y108593D03*
Y104577D03*
X320500Y100400D03*
X331881Y112608D03*
X320765Y114582D03*
X320938Y122677D03*
X318000Y117200D03*
X329297Y134594D03*
Y129890D03*
X321276Y134532D03*
X321349Y130044D03*
X331741Y138243D03*
Y125796D03*
X320239Y151075D03*
X328087Y141608D03*
X331641Y141743D03*
X321600Y142100D03*
X323384Y157378D03*
X331405Y157411D03*
X323384Y165378D03*
Y161378D03*
X331405Y164911D03*
Y159911D03*
Y154911D03*
X323384Y169378D03*
Y173378D03*
Y177378D03*
X331405Y177411D03*
Y179911D03*
Y174911D03*
Y169911D03*
Y182926D03*
Y187411D03*
Y192411D03*
Y189911D03*
X319601Y201140D03*
X326932Y205685D03*
X326733Y209885D03*
X321045Y210257D03*
X320937Y212839D03*
X326733Y201485D03*
X326323Y226349D03*
X317922Y226373D03*
X326731Y213648D03*
X320931Y215387D03*
X326323Y229738D03*
X317922Y229762D03*
X317670Y291430D03*
X330900Y314700D03*
X325007Y328608D03*
Y326008D03*
X327704Y328635D03*
Y326035D03*
X325007Y323508D03*
X327704Y323535D03*
X325038Y356890D03*
X325900Y365643D03*
X326100Y375717D03*
X326200Y370681D03*
X325320Y390118D03*
X325200Y383900D03*
X326375Y380724D03*
X332470Y397092D03*
Y394092D03*
X325593Y406500D03*
X329093D03*
X318593D03*
X322093D03*
X331646Y466536D03*
X342218Y3000D03*
X337375Y76600D03*
X342900Y66100D03*
X339900Y66000D03*
X342200Y100500D03*
X342180Y106900D03*
X339101Y117328D03*
Y121128D03*
X337842Y128533D03*
X333278Y151129D03*
X339800Y154911D03*
Y159911D03*
Y165911D03*
Y169911D03*
Y176911D03*
Y179911D03*
Y185911D03*
Y189911D03*
X337083Y197000D03*
X337004Y202113D03*
Y206113D03*
Y210113D03*
X334723Y226349D03*
Y229738D03*
X336312Y286352D03*
X336461Y283202D03*
X340612Y278972D03*
X339700Y295900D03*
X347100Y313700D03*
X342604Y318773D03*
X345500Y342690D03*
X335475Y358500D03*
X335700Y376400D03*
X335500Y363200D03*
X335475Y367500D03*
X335708Y372008D03*
X334600Y383300D03*
X335500Y380000D03*
X334112Y447668D03*
X351331Y20788D03*
Y40788D03*
Y60788D03*
Y80788D03*
Y100788D03*
Y120788D03*
Y140788D03*
Y160788D03*
Y180788D03*
Y200788D03*
Y220788D03*
Y240788D03*
Y260788D03*
Y280788D03*
Y300788D03*
X349290Y337646D03*
X351331Y357531D03*
Y377531D03*
Y397531D03*
Y417531D03*
Y437531D03*
X375904Y-438145D03*
X375964Y-215959D03*
X375876Y-159873D03*
X375964Y12313D03*
X375904Y68399D03*
X375964Y381585D03*
X379304Y-438145D03*
X379364Y-215959D03*
X379276Y-159873D03*
X379364Y12313D03*
X379304Y68399D03*
X379364Y381585D03*
X396992Y-464207D03*
X400392D03*
X397080Y-121021D03*
X400480D03*
G54D22*
X23819Y339154D03*
Y349154D03*
Y359154D03*
Y369154D03*
Y379154D03*
Y389154D03*
Y399154D03*
Y409154D03*
X65709Y52244D03*
X75709Y42244D03*
Y52244D03*
X95709Y42244D03*
X85709D03*
X95709Y52244D03*
X85709D03*
G54D24*
X63898Y24764D03*
X73898D03*
X90472D03*
X100472D03*
X117047D03*
X127047D03*
X211142D03*
X221142D03*
X237717D03*
X247717D03*
G54D27*
X62458Y346425D03*
Y343275D03*
Y355873D03*
X58564Y354280D03*
X65607Y352724D03*
Y359023D03*
Y371584D03*
X62458Y390481D03*
X75056Y346425D03*
X68757D03*
X81355D03*
X78206Y349574D03*
X68757Y352724D03*
X71906Y355873D03*
X75056Y359023D03*
X65607Y349574D03*
X71906D03*
X68757D03*
X78206Y359023D03*
X75056Y352724D03*
Y349574D03*
X78206Y355873D03*
X65607D03*
X68757Y362173D03*
Y359023D03*
X71906D03*
X75056Y355873D03*
X71906Y352724D03*
X68757Y355873D03*
X78206Y374733D03*
Y362173D03*
X75056D03*
X71906Y371584D03*
X75056Y365322D03*
X71906D03*
X68757D03*
Y371584D03*
X75056Y374733D03*
X71906D03*
X68757D03*
X65607D03*
X71906Y362173D03*
X78206Y365322D03*
Y371584D03*
X75056Y377883D03*
X68757Y384182D03*
X65607Y387332D03*
X75018Y381033D03*
X68757Y377883D03*
X78206Y381033D03*
X65607D03*
X71906Y377883D03*
X65607Y384182D03*
X68719Y381033D03*
X78206Y377883D03*
X71906Y387332D03*
X71869Y381033D03*
X71906Y384182D03*
X87617Y352724D03*
X90766Y349574D03*
X93916Y352724D03*
X81355Y355873D03*
X90766Y352724D03*
X87617Y349574D03*
X90766Y355873D03*
X87617D03*
X90766Y359023D03*
X81355Y349574D03*
X87617Y359023D03*
Y365322D03*
Y371584D03*
X81355Y365322D03*
Y371584D03*
X90766Y374733D03*
Y362173D03*
X81355D03*
X87617D03*
X81355Y374733D03*
X87617D03*
X90766Y371584D03*
Y365322D03*
X81355Y377883D03*
Y387332D03*
Y384182D03*
X87617D03*
X90766Y377883D03*
X87617Y390481D03*
X81355Y381033D03*
X87617Y387332D03*
X90766Y381033D03*
X87617Y377883D03*
X90766Y390481D03*
Y387332D03*
Y384182D03*
X92360Y394175D03*
X89210D03*
X103365Y346425D03*
X106564Y346400D03*
X100253Y346387D03*
X100215Y352724D03*
X103383Y349556D03*
X93916Y359023D03*
X97066Y355873D03*
X93916Y349574D03*
X97066D03*
X106515Y352724D03*
X106514Y349574D03*
X97066Y352724D03*
X100215Y355873D03*
X93916D03*
X100215Y349574D03*
X103383Y387350D03*
X100215Y384182D03*
X93916Y377883D03*
X97066Y381033D03*
X100215Y387332D03*
X97066D03*
X93916Y384182D03*
X97066D03*
X100215Y381033D03*
X93916D03*
Y387332D03*
X166300Y212300D03*
X175359Y153286D03*
X181495Y153449D03*
X175196Y159748D03*
X178346Y162898D03*
Y156599D03*
X181495Y159748D03*
X175196Y156599D03*
X181495D03*
Y166047D03*
X184645D03*
X181495Y162898D03*
X178346Y159748D03*
Y172347D03*
X181495Y178646D03*
Y175496D03*
X184645Y181795D03*
X181495D03*
Y172347D03*
X184645Y175496D03*
X174569Y180202D03*
X178346Y175496D03*
X175196Y172347D03*
X173000Y170200D03*
X181495Y169197D03*
X178346Y184945D03*
X181495D03*
Y197506D03*
X178346D03*
Y191244D03*
X181495D03*
X175196Y197506D03*
X174336Y192800D03*
X181495Y188095D03*
X178346D03*
X175196Y200655D03*
X178346D03*
Y210104D03*
X181495Y203805D03*
Y206955D03*
X175196Y210104D03*
X178346Y206955D03*
X175196D03*
Y203805D03*
X178346D03*
X171836Y200655D03*
Y198300D03*
X181495Y200655D03*
X178346Y213254D03*
Y225852D03*
X181495Y219553D03*
X175196Y213254D03*
X184645Y219553D03*
X178346Y229002D03*
X181495Y225852D03*
Y222703D03*
X184645Y229002D03*
X174600Y217800D03*
X181495Y216403D03*
X174079Y234604D03*
X175196Y229002D03*
X181495D03*
X187794Y153449D03*
X192400Y152804D03*
X184645Y153449D03*
X197243Y156599D03*
X187794Y159748D03*
X197243Y166047D03*
X194094Y162898D03*
X197243Y159748D03*
X194094D03*
X197243Y162898D03*
X184645Y156599D03*
X187794Y162898D03*
Y166047D03*
X184645Y162898D03*
Y159748D03*
X190944Y162898D03*
Y159748D03*
X194094Y166047D03*
X190944D03*
X200393Y162898D03*
X187794Y156599D03*
Y178646D03*
X197243D03*
X187794Y181795D03*
X194094Y169197D03*
X190944Y172347D03*
Y175496D03*
X197243D03*
X190944Y178646D03*
Y181795D03*
X187794Y175496D03*
X184645Y178646D03*
X190944Y169197D03*
X187794Y172347D03*
X184645Y169197D03*
Y172347D03*
X187794Y169197D03*
X197243Y191244D03*
Y197506D03*
X187794D03*
Y184945D03*
X184645Y197506D03*
Y184945D03*
Y191244D03*
Y188095D03*
X197243Y203805D03*
X184645Y206955D03*
X197243Y200655D03*
X190944Y210104D03*
Y203805D03*
X187794Y200655D03*
X184645Y210104D03*
Y200655D03*
Y203805D03*
X187794Y210104D03*
X190944Y219553D03*
X194094Y222703D03*
X200393Y229002D03*
X194094Y225852D03*
X187794D03*
Y219553D03*
X197243D03*
X187794Y213254D03*
X190944D03*
Y222702D03*
X200393Y222703D03*
X197243Y225852D03*
Y222703D03*
X184645Y225852D03*
X187794Y222703D03*
X184645D03*
Y213254D03*
X194094Y219553D03*
Y232151D03*
X184645D03*
X187794Y229002D03*
X197243Y235301D03*
X194094Y229002D03*
X197243D03*
Y232151D03*
X209842Y153449D03*
Y159748D03*
X206692Y156599D03*
X209842D03*
X203542Y166047D03*
X206692Y162898D03*
X203542D03*
X200393Y159748D03*
X209842Y166047D03*
Y162898D03*
X212991D03*
X203542Y159748D03*
X200393Y166047D03*
X206692D03*
X212991D03*
X206692Y159748D03*
X209842Y169197D03*
X203542D03*
X212991D03*
X206692D03*
X212991Y181795D03*
X206692Y178646D03*
X209842Y181795D03*
X200393Y169197D03*
X203542Y175496D03*
X206692D03*
X209842D03*
X200393D03*
X203542Y191244D03*
X206692D03*
X209842Y184945D03*
X200393Y191244D03*
X203542Y197506D03*
X209842D03*
X203542Y210104D03*
X212991Y206955D03*
Y210104D03*
X209842D03*
X200393D03*
X203542Y200655D03*
X209842D03*
X212991Y219553D03*
Y213254D03*
X200393D03*
Y219553D03*
X212991Y222740D03*
X209842Y213254D03*
Y225852D03*
X203542Y222703D03*
X200393Y225852D03*
X206692Y219553D03*
X203542Y225852D03*
X206692Y229002D03*
X212991D03*
X203542Y219553D03*
X206692Y222703D03*
X209842D03*
X212991Y225890D03*
X206692Y225852D03*
X203542Y229002D03*
Y232151D03*
X209746Y235397D03*
X203542Y235301D03*
X209842Y232151D03*
X200393D03*
X206692D03*
X212991D03*
X209842Y229002D03*
X225658Y153369D03*
X225552Y156599D03*
Y159748D03*
X222402Y162898D03*
X219253Y166047D03*
X225552Y162898D03*
Y166047D03*
X222402D03*
X219253Y159748D03*
X222402D03*
X219253Y162898D03*
Y156599D03*
X222402D03*
X217697Y174852D03*
X219253Y178646D03*
X225552D03*
X222402Y169197D03*
Y178646D03*
X225552Y181795D03*
X214547Y174852D03*
X225552Y169197D03*
X219253D03*
X219290Y191207D03*
X225552Y184945D03*
Y197543D03*
X222402Y191244D03*
X219253Y197506D03*
X222402D03*
X219253Y188095D03*
X222402Y206955D03*
X219253Y200655D03*
Y206955D03*
Y210104D03*
Y203805D03*
X222402Y213254D03*
X219253D03*
X228739Y222703D03*
X216141D03*
X228702Y229002D03*
X225590Y222720D03*
X216103Y219591D03*
X219253Y219553D03*
X225590Y225852D03*
X222440Y222703D03*
X225552Y219553D03*
X222402D03*
Y229002D03*
X222440Y225852D03*
X219290D03*
Y222703D03*
X219253Y232151D03*
X225552Y229002D03*
X219253D03*
X235001Y153449D03*
X228702Y162898D03*
X238150D03*
X235001Y166047D03*
X231851D03*
X238150D03*
X228702Y159748D03*
Y166047D03*
X238150Y156599D03*
X235001D03*
X231851D03*
Y162898D03*
Y159748D03*
X235001Y162898D03*
Y159748D03*
X238150D03*
X241300D03*
X228702Y169197D03*
X238150D03*
X231851D03*
Y178646D03*
X235001Y169197D03*
Y178646D03*
Y175496D03*
X228702Y181795D03*
Y178646D03*
X231851Y191244D03*
X241300D03*
X235001Y184945D03*
X228702Y191244D03*
X241300Y188095D03*
X235001Y200655D03*
Y206955D03*
X244450Y200655D03*
X235001Y203805D03*
X231851D03*
X228702D03*
X241300Y210104D03*
X235001D03*
X231851D03*
X228702D03*
X235001Y219553D03*
X241300Y213254D03*
X238150Y219553D03*
X238188Y225852D03*
X228702Y219553D03*
X228739Y213254D03*
X235038Y225890D03*
X228739Y225852D03*
X238150Y222703D03*
X231889Y219591D03*
Y222740D03*
X235038D03*
X231889Y225890D03*
X228739Y216441D03*
X241338Y225890D03*
X238630Y235654D03*
X231851Y232151D03*
X241300D03*
X231851Y229002D03*
X241300D03*
X239870Y237596D03*
X242870D03*
X235038Y229039D03*
X255492Y152905D03*
X244450Y156599D03*
X250749Y159748D03*
X244450D03*
X250749Y169197D03*
X247637Y162898D03*
X247599Y166047D03*
X253898Y172347D03*
Y178646D03*
X247599Y181795D03*
Y175496D03*
X253898Y169197D03*
X257048Y172347D03*
X250749Y181795D03*
X244450D03*
X250749Y175496D03*
Y178646D03*
X247599Y172347D03*
X244450Y175496D03*
X250749Y172347D03*
X247599Y178646D03*
X253898Y175496D03*
X244450Y178646D03*
Y172347D03*
X250749Y184945D03*
X244450Y169197D03*
X253898Y191244D03*
Y184945D03*
X247599Y197506D03*
Y188095D03*
X244450Y197506D03*
X247599Y191244D03*
X257048Y197506D03*
X253898D03*
X250749D03*
X247599Y184945D03*
X244450Y188095D03*
X257048Y191244D03*
X250749Y188095D03*
X244450Y184945D03*
X250749Y191244D03*
X244450D03*
X247599Y203805D03*
X253898Y206955D03*
Y200655D03*
X250749Y203805D03*
X247599Y206955D03*
Y210104D03*
X250749Y206955D03*
X247599Y200655D03*
X257048Y206955D03*
X250749Y200655D03*
X257048D03*
X250749Y210104D03*
X244450Y203805D03*
X250749Y222703D03*
Y225852D03*
X253898Y219553D03*
Y222703D03*
X257048Y225890D03*
Y219553D03*
X250749D03*
X257048Y213254D03*
X250749D03*
X247599D03*
X253898D03*
X247637Y225852D03*
X250749Y232151D03*
X257048Y235301D03*
X244020Y235518D03*
X244487Y229002D03*
X244450Y232151D03*
X247599D03*
X253898D03*
X257048D03*
X250749Y229002D03*
X253898D03*
X250749Y235301D03*
X253898D03*
X268510Y179088D03*
X262880Y178977D03*
X267722Y176791D03*
X264222D03*
X271209Y177524D03*
X270472Y188488D03*
X264118Y188095D03*
X268391Y207262D03*
X260269Y207358D03*
X266080Y207262D03*
X262580D03*
X269391Y214593D03*
X261269Y214657D03*
X263580Y214593D03*
X267080D03*
X285980Y163487D03*
X286105Y172936D03*
Y182385D03*
X273644Y174267D03*
X282975Y172975D03*
X286105Y176085D03*
X285482Y190187D03*
X286105Y197989D03*
X289254Y194839D03*
X286105Y201139D03*
X286106Y210587D03*
X289110Y163487D03*
X292260D03*
X295410Y169786D03*
X292404Y176085D03*
X295410Y172936D03*
X289254Y172792D03*
X292260Y169643D03*
X295410Y179235D03*
X292384Y172936D03*
X289254Y176085D03*
Y182385D03*
X292260Y179235D03*
X297372Y196616D03*
X292361Y197970D03*
X292404Y191690D03*
X289254D03*
X292404Y185534D03*
Y194983D03*
X295410Y194839D03*
X295411Y185534D03*
X289091Y204331D03*
X289254Y210587D03*
X298714Y210477D03*
X292404Y210587D03*
Y201282D03*
X299667Y201334D03*
X292404Y213737D03*
X289254Y201139D03*
Y213737D03*
X308008Y163487D03*
X311158D03*
X308008Y166637D03*
X314930Y168140D03*
X311301Y182385D03*
X314930Y171289D03*
Y177588D03*
X305002Y176085D03*
Y169786D03*
Y172936D03*
X308152Y169786D03*
X311158Y169643D03*
X308152Y172936D03*
Y176085D03*
Y182385D03*
X305002Y179235D03*
X308152D03*
X314930Y174439D03*
X311158Y185534D03*
X314307Y191690D03*
X311158Y194839D03*
X308008Y191690D03*
X311158D03*
X308008Y188540D03*
Y185391D03*
Y198133D03*
X314307Y197989D03*
X311158Y204288D03*
X314307Y207438D03*
X303940Y212664D03*
X311158Y201139D03*
X308008Y207438D03*
X308152Y204432D03*
X305002D03*
X311158Y210587D03*
X308008Y210731D03*
X305002Y210587D03*
X314307Y201139D03*
X308460Y214178D03*
X311158Y213737D03*
G54D36*
X372604Y-455313D03*
Y-430313D03*
X372664Y-223791D03*
Y-198791D03*
X372576Y-177041D03*
Y-152041D03*
X372664Y4481D03*
Y29481D03*
X372604Y51231D03*
Y76231D03*
X372664Y373753D03*
Y398753D03*
X393692Y-481375D03*
X382604Y-455313D03*
X393692Y-456375D03*
X382604Y-430313D03*
X382664Y-223791D03*
Y-198791D03*
X382576Y-177041D03*
Y-152041D03*
X393780Y-128853D03*
Y-103853D03*
X393750Y-82222D03*
Y-57222D03*
X382664Y4481D03*
Y29481D03*
X382604Y51231D03*
Y76231D03*
X393750Y200538D03*
Y225538D03*
Y247050D03*
Y272050D03*
X382664Y373753D03*
X393750Y398810D03*
X382664Y398753D03*
X393750Y423810D03*
X403692Y-481375D03*
Y-456375D03*
X403780Y-128853D03*
Y-103853D03*
X403750Y-82222D03*
D03*
Y-57222D03*
D03*
Y200538D03*
D03*
Y225538D03*
D03*
Y247050D03*
D03*
Y272050D03*
D03*
Y398810D03*
D03*
Y423810D03*
D03*
X413750Y-82222D03*
Y-57222D03*
Y200538D03*
Y225538D03*
Y247050D03*
Y272050D03*
Y398810D03*
Y423810D03*
G54D21*
X25200Y116300D03*
X39493Y222932D03*
X41993D03*
X44149Y227332D03*
X39493Y220332D03*
X41993D03*
X44149Y224732D03*
X74757Y89745D03*
Y92745D03*
Y86745D03*
Y83745D03*
X91358Y89745D03*
Y92745D03*
Y86745D03*
Y83745D03*
X279457Y171318D03*
X295410Y210587D03*
X301120Y235626D03*
Y238765D03*
X309521Y235352D03*
Y238741D03*
X317922Y238717D03*
Y235328D03*
X326323Y235304D03*
Y238693D03*
X334724Y238669D03*
Y235280D03*
X337467Y236984D03*
X373480Y-210223D03*
X370965D03*
Y-206970D03*
X376406Y-206985D03*
X373480Y-206970D03*
X372271Y-213263D03*
X373480Y18049D03*
X370965D03*
X372271Y15009D03*
X370965Y21302D03*
X376406Y21287D03*
X373480Y21302D03*
X372271Y384281D03*
X376406Y390559D03*
X373480Y387321D03*
Y390574D03*
X370965Y387321D03*
Y390574D03*
X383057Y-213263D03*
X381848Y-206970D03*
X384363D03*
Y-210223D03*
X381848D03*
X378922Y-206970D03*
X392081Y-115285D03*
Y-112032D03*
X383057Y15009D03*
X384363Y18049D03*
X381848D03*
Y21302D03*
X384363D03*
X378922D03*
X391950Y214106D03*
Y217359D03*
X378922Y390574D03*
X381848D03*
Y387321D03*
X384363Y390574D03*
Y387321D03*
X383057Y384281D03*
X391950Y412378D03*
Y415631D03*
X394596Y-115285D03*
X393387Y-118325D03*
X404173D03*
X405479Y-115285D03*
X402964D03*
X397522Y-112047D03*
X394596Y-112032D03*
X402964D03*
X405479D03*
X400038D03*
X393357Y211066D03*
X403857D03*
X394450Y217359D03*
Y214106D03*
X396950Y217359D03*
X399450Y217344D03*
X402450Y217359D03*
X404950D03*
X402450Y214106D03*
X404950D03*
X394450Y415631D03*
Y412378D03*
X396950Y415631D03*
X399450Y415616D03*
X393357Y409338D03*
X402450Y415631D03*
X404950D03*
X402450Y412378D03*
X404950D03*
X403857Y409338D03*
X414143Y211066D03*
X415550Y214106D03*
Y217359D03*
X413050D03*
Y214106D03*
X410550Y217359D03*
X408050Y217344D03*
X415550Y412378D03*
Y415631D03*
X413050D03*
Y412378D03*
X410550Y415631D03*
X408050Y415616D03*
X414143Y409338D03*
G54D23*
X48500Y112559D03*
X138590Y345710D03*
X151320Y322700D03*
X143945Y354146D03*
X172530Y429470D03*
X190944Y197506D03*
Y188095D03*
Y191244D03*
Y200655D03*
X190900Y271700D03*
X192448Y308314D03*
X206692Y181795D03*
X212991Y184945D03*
Y197506D03*
X203542Y206955D03*
X212991Y203805D03*
X206692Y206955D03*
X209842D03*
X200393D03*
X212991Y200655D03*
X225552Y191244D03*
Y188095D03*
X241300Y175496D03*
Y178646D03*
Y172347D03*
X235001Y188095D03*
Y191244D03*
Y197506D03*
X241300Y184945D03*
Y197506D03*
Y200655D03*
X287761Y366200D03*
X287500Y376900D03*
X295500Y354920D03*
G54D34*
X285482Y168102D03*
G54D38*
X441000Y-454000D03*
X451000D03*
X441000Y-333400D03*
X451000D03*
X441000Y2000D03*
X451000D03*
X441000Y116000D03*
X451000D03*
G54D15*
X17716Y18465D03*
X45276D03*
X264173Y20040D03*
X291733D03*
X309055Y18465D03*
X336615D03*
G54D31*
X153237Y58583D03*
X165048Y52677D03*
X155205D03*
X161111Y58583D03*
X168985D03*
X182764Y52677D03*
X172922D03*
X176859Y58583D03*
X184733D03*
G54D37*
X441000Y-444000D03*
X451000D03*
Y-355000D03*
X441000D03*
Y-323400D03*
X451000D03*
Y-245000D03*
X441000D03*
X451000Y-215000D03*
X441000D03*
Y-136600D03*
X451000D03*
Y-107000D03*
X441000D03*
Y-18000D03*
X451000D03*
X441000Y12000D03*
X451000D03*
Y96000D03*
X441000D03*
Y126000D03*
X451000D03*
Y200000D03*
X441000D03*
X451000Y230000D03*
X441000D03*
Y304000D03*
X451000D03*
Y336000D03*
X441000D03*
Y420000D03*
X451000D03*
G54D41*
X441000Y-126600D03*
X451000D03*
X441000Y-8000D03*
X451000D03*
X441000Y314000D03*
X451000D03*
X441000Y430000D03*
X451000D03*
G54D11*
X-61709Y56192D03*
X-51709D03*
X-61100Y250316D03*
X-61000Y382816D03*
X-51100Y250316D03*
X-51000Y382816D03*
X-35000Y56184D03*
X-25000D03*
X-25100Y250316D03*
X-35100D03*
X-36000Y418816D03*
X-26000D03*
G54D26*
X65945Y297776D03*
G54D32*
X144685D03*
G54D25*
X65709Y42244D03*
G54D10*
X-56709Y43008D03*
X-30000Y43000D03*
G54D30*
X143118Y44803D03*
X194851D03*
G54D28*
X105315Y186571D03*
G54D29*
X105316Y213343D03*
G54D17*
X24016Y89331D03*
X330315D03*
G54D33*
X236220Y424016D03*
X301181D03*
G54D16*
X22047Y46417D03*
X333466D03*
G54D20*
X27300Y68200D03*
X340639Y432809D03*
G54D19*
X13736Y299891D03*
Y303280D03*
X22237Y304626D03*
X30638Y304602D03*
X22237Y301237D03*
X30638Y301213D03*
X47440Y304225D03*
X39039Y301299D03*
X47440Y301336D03*
X39039Y304278D03*
X68990Y257000D03*
X90800Y258225D03*
X97177Y263320D03*
X120800Y147200D03*
X117800D03*
X141520Y399700D03*
X149600Y410500D03*
X289111Y179235D03*
X311158Y188540D03*
X373420Y-447134D03*
X370905D03*
Y-443881D03*
X373420D03*
X376346Y-447134D03*
X372211Y-440841D03*
X372183Y-162569D03*
X373392Y-168862D03*
X370877D03*
Y-165609D03*
X373392D03*
X376318Y-168862D03*
X373420Y59410D03*
X370905D03*
Y62663D03*
X373420D03*
X376346Y59410D03*
X372211Y65703D03*
X391993Y-473196D03*
Y-469943D03*
X381788Y-443881D03*
X384303D03*
Y-447134D03*
X378862Y-447119D03*
X381788Y-447134D03*
X382997Y-440841D03*
X381760Y-165609D03*
X384275D03*
Y-168862D03*
X378834Y-168847D03*
X381760Y-168862D03*
X382969Y-162569D03*
X391950Y-74043D03*
Y-70790D03*
X381788Y62663D03*
X384303D03*
Y59410D03*
X378862Y59425D03*
X381788Y59410D03*
X382997Y65703D03*
X391950Y255229D03*
Y258482D03*
X405391Y-473196D03*
X399950Y-473181D03*
X402876Y-473196D03*
X394508D03*
X397434D03*
X402876Y-469943D03*
X405391D03*
X404085Y-466903D03*
X393299D03*
X394508Y-469943D03*
X399450Y-74028D03*
X394450Y-74043D03*
Y-70790D03*
X396950Y-74043D03*
X405050D03*
X402550D03*
X405050Y-70790D03*
X402550D03*
X393357Y-67750D03*
X403643D03*
X394450Y255229D03*
X396950D03*
X399450Y255244D03*
X405050Y255229D03*
X402550D03*
X394450Y258482D03*
X393357Y261522D03*
X405050Y258482D03*
X402550D03*
X403643Y261522D03*
X415550Y-70790D03*
Y-74043D03*
X413050D03*
Y-70790D03*
X410550Y-74043D03*
X408050Y-74028D03*
X414143Y-67750D03*
X415550Y255229D03*
X413050D03*
X410550D03*
X408050Y255244D03*
X415550Y258482D03*
X413050D03*
X414143Y261522D03*
G54D35*
X314930Y180738D03*
G54D18*
X19200Y102700D03*
X17700Y427600D03*
X30700Y315500D03*
X20600Y428900D03*
X45500Y41500D03*
X35304Y58317D03*
X51500Y258200D03*
X44200Y332000D03*
X37875Y377925D03*
X44525Y387800D03*
X44490Y397850D03*
X41200Y429100D03*
X58976Y36402D03*
X53434Y106562D03*
X52050Y208760D03*
X50567Y238630D03*
X56600Y320500D03*
X52900Y360000D03*
X52600Y376600D03*
X68500Y66500D03*
X77900Y274700D03*
X70000Y280000D03*
X72700Y301200D03*
X71000Y394400D03*
X68100Y425400D03*
X86100Y153340D03*
Y155840D03*
X83410Y161020D03*
X86100Y158390D03*
X83520Y158520D03*
X90500Y397600D03*
X82500D03*
X87600Y414500D03*
X98500Y66500D03*
X108800Y91900D03*
X102600Y267000D03*
X105755Y327719D03*
X98100Y412400D03*
X119000Y44600D03*
X119700Y89200D03*
X115025Y104800D03*
X115400Y159500D03*
X111400Y254680D03*
X117400Y266500D03*
X111100Y273700D03*
X121175Y385125D03*
X119200Y406175D03*
X119791Y412301D03*
X126425Y57000D03*
X132828Y138400D03*
X126500Y174000D03*
X133000Y256100D03*
X128760Y265726D03*
X135315Y279813D03*
X125100Y273720D03*
X124400Y345300D03*
X125910Y335006D03*
X133000Y361500D03*
X136230Y423935D03*
X148819Y123197D03*
X143400Y121700D03*
X141220Y123070D03*
X148819Y125697D03*
X140554Y168887D03*
Y171688D03*
X151940Y203710D03*
X152500Y289425D03*
X148600Y336300D03*
X142202Y334000D03*
X148316Y359086D03*
X139700Y415100D03*
X150000Y414750D03*
X148100Y433400D03*
X155530Y116640D03*
X156467Y203500D03*
X162160Y313560D03*
X168557Y341221D03*
X161300Y354600D03*
X157294Y435623D03*
X181960Y99260D03*
X179500Y116800D03*
X176900Y270100D03*
X180600Y360200D03*
X184800Y100300D03*
X190800Y117200D03*
X193096Y115600D03*
X197243Y184945D03*
X190944D03*
X196240Y253430D03*
X195370Y273297D03*
X187623Y297475D03*
X196050Y358770D03*
X189762Y429177D03*
X201900Y83300D03*
X199940Y117500D03*
X211370Y117000D03*
X205500Y258300D03*
X198672Y318175D03*
X198600Y426600D03*
X215294Y117094D03*
X219722Y286728D03*
X214400Y303997D03*
X225867Y345033D03*
X224632Y369825D03*
X225700Y362500D03*
X220515Y384900D03*
X219050Y418850D03*
X234537Y74638D03*
X230600Y91700D03*
X240160Y107000D03*
X240710Y99570D03*
X238900Y114800D03*
X228702Y200655D03*
X240500Y316575D03*
X239750Y394970D03*
X252925Y54000D03*
X246200Y74600D03*
X255000Y82700D03*
X243750Y369730D03*
X271602Y121400D03*
X266250Y297900D03*
X271100Y346575D03*
X265320Y392290D03*
X277000Y51665D03*
X274500Y58000D03*
X283500Y126000D03*
X287555Y142419D03*
X286105Y185534D03*
Y194839D03*
Y204288D03*
Y213721D03*
X285911Y269899D03*
X281889D03*
X275700Y403500D03*
X300425Y54516D03*
X290000Y67975D03*
X300070Y84000D03*
X292204Y142610D03*
X301936Y143897D03*
X289254Y185534D03*
Y197989D03*
X296734Y216079D03*
X316025Y60200D03*
X309570Y84000D03*
X316066Y108407D03*
X315900Y125900D03*
X305936Y143897D03*
X309936D03*
X313936D03*
X314307Y163487D03*
Y185534D03*
X308008Y194839D03*
X311158Y197989D03*
X314307Y194839D03*
Y204288D03*
Y210587D03*
X307487Y219503D03*
X304987D03*
X310449Y218617D03*
X314307Y213737D03*
X306500Y301500D03*
X303000Y309200D03*
X306200Y308800D03*
X308906Y362637D03*
X324011Y118843D03*
X324023Y121943D03*
Y115643D03*
X317936Y143897D03*
X323509Y153377D03*
X329005Y152657D03*
X331405Y167411D03*
Y172411D03*
X320054Y195163D03*
Y198663D03*
X327162Y278972D03*
X329925Y356016D03*
X331500Y383300D03*
X339900Y69100D03*
X339908Y104577D03*
Y108593D03*
Y112609D03*
X339369Y151952D03*
X339939Y162911D03*
X339812Y173380D03*
X339800Y182926D03*
X337400Y193449D03*
X339700Y293000D03*
X374975Y-435380D03*
X374666Y-218571D03*
X374947Y-157108D03*
X374666Y9701D03*
X374975Y71164D03*
X374666Y378973D03*
X380602Y-435533D03*
X380293Y-218724D03*
X380574Y-157261D03*
X380293Y9548D03*
X380602Y71011D03*
X380293Y378820D03*
X396063Y-461442D03*
X401690Y-461595D03*
X401409Y-123786D03*
X395782Y-123633D03*
G54D39*
X451000Y-345000D03*
X441000D03*
X451000Y-235000D03*
X441000D03*
X451000Y106000D03*
X441000D03*
X451000Y210000D03*
X441000D03*
G54D40*
X451000Y-225000D03*
X441000D03*
X451000Y-117000D03*
X441000D03*
X451000Y220000D03*
X441000D03*
X451000Y326000D03*
X441000D03*
G54D13*
X-30100Y263500D03*
G54D12*
X-56100D03*
X-56000Y396000D03*
X-31000Y432000D03*
%LPC*%
G75*
G54D42*
G01X2010999Y-388000D02*
Y1475775D01*
X-407000D01*
Y-386798D01*
Y-755294D01*
Y-793716D01*
X-368578D01*
X1942346D01*
X2010999D01*
Y-725063D01*
Y-388000D01*
G01X-53307Y-609436D02*
Y-684436D01*
X446693D01*
Y-609436D01*
X-53307D01*
G01X-41307Y-674436D02*
Y-679436D01*
G01X-42764Y-674436D02*
X-39850D01*
G01X-34940Y-679436D02*
X-37474D01*
Y-674436D01*
X-34940D01*
G01X-35954Y-676853D02*
X-37474D01*
G01X-32374Y-674436D02*
Y-679436D01*
X-29840D01*
G01X-26007Y-679603D02*
X-26134Y-679519D01*
Y-679353D01*
X-26007Y-679269D01*
X-25880Y-679353D01*
Y-679519D01*
X-26007Y-679603D01*
G01Y-677353D02*
X-26134Y-677269D01*
Y-677103D01*
X-26007Y-677019D01*
X-25880Y-677103D01*
Y-677269D01*
X-26007Y-677353D01*
G01X-21224Y-681103D02*
X-21857Y-680269D01*
X-22174Y-679436D01*
Y-676103D01*
X-21857Y-675269D01*
X-21224Y-674436D01*
G01X-15807D02*
X-16314Y-674603D01*
X-16694Y-675019D01*
X-16947Y-675519D01*
X-17137Y-676186D01*
X-17200Y-676936D01*
X-17137Y-677686D01*
X-16947Y-678353D01*
X-16694Y-678853D01*
X-16314Y-679269D01*
X-15807Y-679436D01*
X-15300Y-679269D01*
X-14920Y-678853D01*
X-14667Y-678353D01*
X-14477Y-677686D01*
X-14414Y-676936D01*
X-14477Y-676186D01*
X-14667Y-675519D01*
X-14920Y-675019D01*
X-15300Y-674603D01*
X-15807Y-674436D01*
G01X-12100Y-678436D02*
X-11720Y-679019D01*
X-11214Y-679353D01*
X-10644Y-679436D01*
X-10137Y-679353D01*
X-9630Y-678936D01*
X-9314Y-678436D01*
X-9250Y-677936D01*
X-9377Y-677353D01*
X-9820Y-676936D01*
X-10264Y-676769D01*
X-10834D01*
G01X-10264D02*
X-9884Y-676519D01*
X-9567Y-676103D01*
X-9440Y-675603D01*
X-9567Y-675103D01*
X-9884Y-674686D01*
X-10454Y-674436D01*
X-11024Y-674519D01*
X-11594Y-674853D01*
G01X-5290Y-681103D02*
X-4657Y-680269D01*
X-4340Y-679436D01*
Y-676103D01*
X-4657Y-675269D01*
X-5290Y-674436D01*
G01X-1900Y-678436D02*
X-1520Y-679019D01*
X-1014Y-679353D01*
X-444Y-679436D01*
X63Y-679353D01*
X570Y-678936D01*
X886Y-678436D01*
X950Y-677936D01*
X823Y-677353D01*
X380Y-676936D01*
X-64Y-676769D01*
X-634D01*
G01X-64D02*
X316Y-676519D01*
X633Y-676103D01*
X760Y-675603D01*
X633Y-675103D01*
X316Y-674686D01*
X-254Y-674436D01*
X-824Y-674519D01*
X-1394Y-674853D01*
G01X3390Y-675269D02*
X3770Y-674769D01*
X4213Y-674519D01*
X4720Y-674436D01*
X5353Y-674603D01*
X5796Y-675019D01*
X5923Y-675519D01*
X5860Y-676019D01*
X5606Y-676436D01*
X4340Y-677269D01*
X3770Y-677853D01*
X3390Y-678686D01*
X3263Y-679436D01*
X5923D01*
G01X9566D02*
X9693Y-678353D01*
X9883Y-677436D01*
X10136Y-676603D01*
X10453Y-675686D01*
X10960Y-674436D01*
X8426D01*
G01X13970Y-677769D02*
X15616D01*
G01X18690Y-675269D02*
X19070Y-674769D01*
X19513Y-674519D01*
X20020Y-674436D01*
X20653Y-674603D01*
X21096Y-675019D01*
X21223Y-675519D01*
X21160Y-676019D01*
X20906Y-676436D01*
X19640Y-677269D01*
X19070Y-677853D01*
X18690Y-678686D01*
X18563Y-679436D01*
X21223D01*
G01X23600Y-678436D02*
X23980Y-679019D01*
X24486Y-679353D01*
X25056Y-679436D01*
X25563Y-679353D01*
X26070Y-678936D01*
X26386Y-678436D01*
X26450Y-677936D01*
X26323Y-677353D01*
X25880Y-676936D01*
X25436Y-676769D01*
X24866D01*
G01X25436D02*
X25816Y-676519D01*
X26133Y-676103D01*
X26260Y-675603D01*
X26133Y-675103D01*
X25816Y-674686D01*
X25246Y-674436D01*
X24676Y-674519D01*
X24106Y-674853D01*
G01X30853Y-679436D02*
Y-674436D01*
X28510Y-678019D01*
X31676D01*
G01X33800Y-678686D02*
X34180Y-679103D01*
X34623Y-679353D01*
X35193Y-679436D01*
X35763Y-679269D01*
X36206Y-678936D01*
X36523Y-678353D01*
X36586Y-677686D01*
X36460Y-677019D01*
X36143Y-676603D01*
X35700Y-676269D01*
X35256Y-676186D01*
X34813Y-676269D01*
X34243Y-676603D01*
X34433Y-674436D01*
X36143D01*
G01X44190Y-679436D02*
Y-674436D01*
X46596D01*
G01X45710Y-676853D02*
X44190D01*
G01X48910Y-679436D02*
X50493Y-674436D01*
X52076Y-679436D01*
G01X51506Y-677686D02*
X49480D01*
G01X54263Y-679436D02*
X56923Y-674436D01*
G01X54263D02*
X56923Y-679436D01*
G01X60693Y-679603D02*
X60566Y-679519D01*
Y-679353D01*
X60693Y-679269D01*
X60820Y-679353D01*
Y-679519D01*
X60693Y-679603D01*
G01Y-677353D02*
X60566Y-677269D01*
Y-677103D01*
X60693Y-677019D01*
X60820Y-677103D01*
Y-677269D01*
X60693Y-677353D01*
G01X65476Y-681103D02*
X64843Y-680269D01*
X64526Y-679436D01*
Y-676103D01*
X64843Y-675269D01*
X65476Y-674436D01*
G01X70893D02*
X70386Y-674603D01*
X70006Y-675019D01*
X69753Y-675519D01*
X69563Y-676186D01*
X69500Y-676936D01*
X69563Y-677686D01*
X69753Y-678353D01*
X70006Y-678853D01*
X70386Y-679269D01*
X70893Y-679436D01*
X71400Y-679269D01*
X71780Y-678853D01*
X72033Y-678353D01*
X72223Y-677686D01*
X72286Y-676936D01*
X72223Y-676186D01*
X72033Y-675519D01*
X71780Y-675019D01*
X71400Y-674603D01*
X70893Y-674436D01*
G01X74600Y-678436D02*
X74980Y-679019D01*
X75486Y-679353D01*
X76056Y-679436D01*
X76563Y-679353D01*
X77070Y-678936D01*
X77386Y-678436D01*
X77450Y-677936D01*
X77323Y-677353D01*
X76880Y-676936D01*
X76436Y-676769D01*
X75866D01*
G01X76436D02*
X76816Y-676519D01*
X77133Y-676103D01*
X77260Y-675603D01*
X77133Y-675103D01*
X76816Y-674686D01*
X76246Y-674436D01*
X75676Y-674519D01*
X75106Y-674853D01*
G01X81410Y-681103D02*
X82043Y-680269D01*
X82360Y-679436D01*
Y-676103D01*
X82043Y-675269D01*
X81410Y-674436D01*
G01X84800Y-678436D02*
X85180Y-679019D01*
X85686Y-679353D01*
X86256Y-679436D01*
X86763Y-679353D01*
X87270Y-678936D01*
X87586Y-678436D01*
X87650Y-677936D01*
X87523Y-677353D01*
X87080Y-676936D01*
X86636Y-676769D01*
X86066D01*
G01X86636D02*
X87016Y-676519D01*
X87333Y-676103D01*
X87460Y-675603D01*
X87333Y-675103D01*
X87016Y-674686D01*
X86446Y-674436D01*
X85876Y-674519D01*
X85306Y-674853D01*
G01X90216Y-678853D02*
X90660Y-679269D01*
X91166Y-679436D01*
X91673Y-679269D01*
X92116Y-678769D01*
X92433Y-678019D01*
X92560Y-677269D01*
Y-676353D01*
X92433Y-675603D01*
X92116Y-674936D01*
X91736Y-674603D01*
X91293Y-674436D01*
X90786Y-674603D01*
X90406Y-674936D01*
X90153Y-675436D01*
X90026Y-676103D01*
X90153Y-676686D01*
X90470Y-677269D01*
X90850Y-677603D01*
X91293Y-677686D01*
X91800Y-677519D01*
X92180Y-677103D01*
X92560Y-676353D01*
G01X96266Y-679436D02*
X96393Y-678353D01*
X96583Y-677436D01*
X96836Y-676603D01*
X97153Y-675686D01*
X97660Y-674436D01*
X95126D01*
G01X100670Y-677769D02*
X102316D01*
G01X105200Y-678436D02*
X105580Y-679019D01*
X106086Y-679353D01*
X106656Y-679436D01*
X107163Y-679353D01*
X107670Y-678936D01*
X107986Y-678436D01*
X108050Y-677936D01*
X107923Y-677353D01*
X107480Y-676936D01*
X107036Y-676769D01*
X106466D01*
G01X107036D02*
X107416Y-676519D01*
X107733Y-676103D01*
X107860Y-675603D01*
X107733Y-675103D01*
X107416Y-674686D01*
X106846Y-674436D01*
X106276Y-674519D01*
X105706Y-674853D01*
G01X110490Y-677353D02*
X110933Y-676769D01*
X111313Y-676436D01*
X111820Y-676269D01*
X112263Y-676436D01*
X112580Y-676769D01*
X112833Y-677269D01*
X112896Y-677853D01*
X112833Y-678353D01*
X112580Y-678853D01*
X112200Y-679269D01*
X111756Y-679436D01*
X111250Y-679269D01*
X110806Y-678769D01*
X110553Y-678019D01*
X110490Y-677186D01*
X110616Y-676103D01*
X110806Y-675519D01*
X111123Y-674936D01*
X111566Y-674519D01*
X112010Y-674436D01*
X112453Y-674603D01*
X112770Y-675019D01*
G01X116793Y-679436D02*
Y-674436D01*
X116033Y-675436D01*
G01Y-679436D02*
X117553D01*
G01X122653D02*
Y-674436D01*
X120310Y-678019D01*
X123476D01*
G01X141693Y-609436D02*
Y-684436D01*
G01Y-659436D02*
X244693D01*
Y-634436D01*
G01X141693D02*
X244693D01*
G01X246693Y-609436D02*
Y-684436D01*
G01X244693Y-609436D02*
Y-684436D01*
G01X252200Y-669436D02*
Y-664436D01*
X253466D01*
X253973Y-664686D01*
X254353Y-665019D01*
X254670Y-665519D01*
X254923Y-666103D01*
X254986Y-666936D01*
X254923Y-667769D01*
X254670Y-668353D01*
X254353Y-668853D01*
X253973Y-669186D01*
X253466Y-669436D01*
X252200D01*
G01X257110D02*
X258693Y-664436D01*
X260276Y-669436D01*
G01X259706Y-667686D02*
X257680D01*
G01X263793Y-664436D02*
Y-669436D01*
G01X262336Y-664436D02*
X265250D01*
G01X270160Y-669436D02*
X267626D01*
Y-664436D01*
X270160D01*
G01X269146Y-666853D02*
X267626D01*
G01X273993Y-669603D02*
X273866Y-669519D01*
Y-669353D01*
X273993Y-669269D01*
X274120Y-669353D01*
Y-669519D01*
X273993Y-669603D01*
G01Y-667353D02*
X273866Y-667269D01*
Y-667103D01*
X273993Y-667019D01*
X274120Y-667103D01*
Y-667269D01*
X273993Y-667353D01*
G01X246693Y-659436D02*
X446693D01*
G01X252326Y-644436D02*
Y-639436D01*
X253846D01*
X254353Y-639686D01*
X254733Y-640269D01*
X254860Y-640936D01*
X254733Y-641603D01*
X254416Y-642103D01*
X253846Y-642353D01*
X252326D01*
G01X257553Y-644603D02*
X259833Y-639436D01*
G01X262336Y-644436D02*
Y-639436D01*
X265250Y-644436D01*
Y-639436D01*
G01X268893Y-644603D02*
X268766Y-644519D01*
Y-644353D01*
X268893Y-644269D01*
X269020Y-644353D01*
Y-644519D01*
X268893Y-644603D01*
G01Y-642353D02*
X268766Y-642269D01*
Y-642103D01*
X268893Y-642019D01*
X269020Y-642103D01*
Y-642269D01*
X268893Y-642353D01*
G01X246693Y-634436D02*
X446693D01*
G01X252326Y-619436D02*
Y-614436D01*
X253846D01*
X254353Y-614686D01*
X254733Y-615269D01*
X254860Y-615936D01*
X254733Y-616603D01*
X254416Y-617103D01*
X253846Y-617353D01*
X252326D01*
G01X257426Y-619436D02*
Y-614436D01*
X259010D01*
X259516Y-614686D01*
X259833Y-615019D01*
X259960Y-615686D01*
X259833Y-616353D01*
X259453Y-616769D01*
X259010Y-617019D01*
X257426D01*
G01X259010D02*
X259960Y-619436D01*
G01X263793D02*
X263286Y-619353D01*
X262843Y-619019D01*
X262463Y-618519D01*
X262210Y-617936D01*
X262083Y-617269D01*
Y-616603D01*
X262210Y-615936D01*
X262463Y-615353D01*
X262843Y-614853D01*
X263286Y-614519D01*
X263793Y-614436D01*
X264300Y-614519D01*
X264743Y-614853D01*
X265123Y-615353D01*
X265376Y-615936D01*
X265503Y-616603D01*
Y-617269D01*
X265376Y-617936D01*
X265123Y-618519D01*
X264743Y-619019D01*
X264300Y-619353D01*
X263793Y-619436D01*
G01X267626Y-618436D02*
X267943Y-618936D01*
X268323Y-619269D01*
X268766Y-619436D01*
X269273Y-619269D01*
X269653Y-618936D01*
X270033Y-618436D01*
X270160Y-617769D01*
Y-614436D01*
G01X275260Y-619436D02*
X272726D01*
Y-614436D01*
X275260D01*
G01X274246Y-616853D02*
X272726D01*
G01X280486Y-614853D02*
X280106Y-614603D01*
X279663Y-614436D01*
X279156D01*
X278586Y-614686D01*
X278143Y-615103D01*
X277826Y-615603D01*
X277573Y-616436D01*
X277510Y-617186D01*
X277636Y-617936D01*
X277826Y-618436D01*
X278206Y-618936D01*
X278650Y-619269D01*
X279093Y-619436D01*
X279536D01*
X279980Y-619269D01*
X280360Y-619019D01*
X280676Y-618686D01*
G01X284193Y-614436D02*
Y-619436D01*
G01X282736Y-614436D02*
X285650D01*
G01X289293Y-619603D02*
X289166Y-619519D01*
Y-619353D01*
X289293Y-619269D01*
X289420Y-619353D01*
Y-619519D01*
X289293Y-619603D01*
G01Y-617353D02*
X289166Y-617269D01*
Y-617103D01*
X289293Y-617019D01*
X289420Y-617103D01*
Y-617269D01*
X289293Y-617353D01*
G01X361693Y-659436D02*
Y-684436D01*
G01X364326Y-661936D02*
Y-666936D01*
X366860D01*
G01X369933Y-661936D02*
X371453D01*
G01X370693D02*
Y-666936D01*
G01X369933D02*
X371453D01*
G01X376300Y-664269D02*
X376553Y-664019D01*
X376743Y-663603D01*
X376870Y-663019D01*
X376743Y-662519D01*
X376490Y-662186D01*
X376046Y-661936D01*
X374336D01*
Y-666936D01*
X376426D01*
X376870Y-666603D01*
X377123Y-666103D01*
X377250Y-665519D01*
X377123Y-664936D01*
X376743Y-664436D01*
X376300Y-664269D01*
X374336D01*
G01X380893Y-667103D02*
X380766Y-667019D01*
Y-666853D01*
X380893Y-666769D01*
X381020Y-666853D01*
Y-667019D01*
X380893Y-667103D01*
G01Y-664853D02*
X380766Y-664769D01*
Y-664603D01*
X380893Y-664519D01*
X381020Y-664603D01*
Y-664769D01*
X380893Y-664853D01*
G01X404693Y-659436D02*
Y-684436D01*
G01Y-634436D02*
Y-659436D01*
G01X412706Y-687603D02*
X412813Y-687478D01*
X412893Y-687269D01*
X412946Y-686978D01*
X412893Y-686728D01*
X412786Y-686561D01*
X412600Y-686436D01*
X411880D01*
Y-688936D01*
X412760D01*
X412946Y-688769D01*
X413053Y-688519D01*
X413106Y-688228D01*
X413053Y-687936D01*
X412893Y-687686D01*
X412706Y-687603D01*
X411880D01*
G01X415173Y-688936D02*
Y-687269D01*
G01Y-687561D02*
X415066Y-687394D01*
X414906Y-687311D01*
X414720Y-687269D01*
X414533Y-687353D01*
X414373Y-687519D01*
X414266Y-687769D01*
X414213Y-688103D01*
X414266Y-688436D01*
X414373Y-688686D01*
X414533Y-688853D01*
X414720Y-688936D01*
X414906Y-688894D01*
X415066Y-688769D01*
X415173Y-688603D01*
G01X416493Y-688644D02*
X416626Y-688811D01*
X416813Y-688936D01*
X416973D01*
X417133Y-688853D01*
X417240Y-688728D01*
X417293Y-688561D01*
X417266Y-688311D01*
X417160Y-688186D01*
X416680Y-687936D01*
X416573Y-687644D01*
X416626Y-687436D01*
X416733Y-687311D01*
X416893Y-687269D01*
X417053Y-687311D01*
X417213Y-687436D01*
G01X418693Y-687811D02*
X419546D01*
X419466Y-687519D01*
X419333Y-687353D01*
X419146Y-687269D01*
X418960Y-687311D01*
X418800Y-687436D01*
X418693Y-687728D01*
X418640Y-687978D01*
Y-688228D01*
X418693Y-688478D01*
X418826Y-688728D01*
X418986Y-688894D01*
X419173Y-688936D01*
X419360Y-688853D01*
X419546Y-688603D01*
G01X420813Y-688936D02*
Y-686436D01*
G01Y-687686D02*
X420946Y-687436D01*
X421106Y-687311D01*
X421266Y-687269D01*
X421506Y-687353D01*
X421666Y-687519D01*
X421773Y-687811D01*
Y-688144D01*
X421720Y-688478D01*
X421613Y-688728D01*
X421426Y-688894D01*
X421266Y-688936D01*
X421106Y-688894D01*
X420946Y-688769D01*
X420813Y-688561D01*
G01X423493Y-688936D02*
X423333Y-688894D01*
X423173Y-688728D01*
X423066Y-688436D01*
X423013Y-688103D01*
X423066Y-687769D01*
X423173Y-687478D01*
X423333Y-687311D01*
X423493Y-687269D01*
X423653Y-687311D01*
X423813Y-687478D01*
X423920Y-687769D01*
X423946Y-688103D01*
X423920Y-688436D01*
X423813Y-688728D01*
X423653Y-688894D01*
X423493Y-688936D01*
G01X426173D02*
Y-687269D01*
G01Y-687561D02*
X426066Y-687394D01*
X425906Y-687311D01*
X425720Y-687269D01*
X425533Y-687353D01*
X425373Y-687519D01*
X425266Y-687769D01*
X425213Y-688103D01*
X425266Y-688436D01*
X425373Y-688686D01*
X425533Y-688853D01*
X425720Y-688936D01*
X425906Y-688894D01*
X426066Y-688769D01*
X426173Y-688603D01*
G01X427520Y-688936D02*
Y-687269D01*
G01Y-687603D02*
X427653Y-687436D01*
X427786Y-687311D01*
X427973Y-687269D01*
X428106Y-687311D01*
X428266Y-687436D01*
G01X430573Y-686436D02*
Y-688936D01*
G01Y-688561D02*
X430466Y-688769D01*
X430306Y-688894D01*
X430120Y-688936D01*
X429906Y-688853D01*
X429746Y-688644D01*
X429640Y-688394D01*
X429613Y-688103D01*
X429640Y-687811D01*
X429746Y-687561D01*
X429906Y-687353D01*
X430120Y-687269D01*
X430306Y-687311D01*
X430440Y-687394D01*
X430573Y-687561D01*
G01X433960Y-688936D02*
Y-686436D01*
X434626D01*
X434840Y-686561D01*
X434973Y-686728D01*
X435026Y-687061D01*
X434973Y-687394D01*
X434813Y-687603D01*
X434626Y-687728D01*
X433960D01*
G01X434626D02*
X435026Y-688936D01*
G01X436293Y-687811D02*
X437146D01*
X437066Y-687519D01*
X436933Y-687353D01*
X436746Y-687269D01*
X436560Y-687311D01*
X436400Y-687436D01*
X436293Y-687728D01*
X436240Y-687978D01*
Y-688228D01*
X436293Y-688478D01*
X436426Y-688728D01*
X436586Y-688894D01*
X436773Y-688936D01*
X436960Y-688853D01*
X437146Y-688603D01*
G01X438413Y-687269D02*
X438893Y-688936D01*
X439373Y-687269D01*
G01X441093Y-689019D02*
X441040Y-688978D01*
Y-688894D01*
X441093Y-688853D01*
X441146Y-688894D01*
Y-688978D01*
X441093Y-689019D01*
G01X443613Y-688936D02*
Y-686436D01*
X442626Y-688228D01*
X443960D01*
G01X444826Y-688936D02*
X445493Y-686436D01*
X446160Y-688936D01*
G01X445920Y-688061D02*
X445066D01*
G01X408593Y-661936D02*
Y-666936D01*
G01X407136Y-661936D02*
X410050D01*
G01X413693Y-666936D02*
X413313Y-666853D01*
X412933Y-666519D01*
X412680Y-665936D01*
X412553Y-665269D01*
X412680Y-664603D01*
X412933Y-664019D01*
X413313Y-663686D01*
X413693Y-663603D01*
X414073Y-663686D01*
X414453Y-664019D01*
X414706Y-664603D01*
X414770Y-665269D01*
X414706Y-665936D01*
X414453Y-666519D01*
X414073Y-666853D01*
X413693Y-666936D01*
G01X418793D02*
X418413Y-666853D01*
X418033Y-666519D01*
X417780Y-665936D01*
X417653Y-665269D01*
X417780Y-664603D01*
X418033Y-664019D01*
X418413Y-663686D01*
X418793Y-663603D01*
X419173Y-663686D01*
X419553Y-664019D01*
X419806Y-664603D01*
X419870Y-665269D01*
X419806Y-665936D01*
X419553Y-666519D01*
X419173Y-666853D01*
X418793Y-666936D01*
G01X423893D02*
Y-661936D01*
G01X428993Y-667103D02*
X428866Y-667019D01*
Y-666853D01*
X428993Y-666769D01*
X429120Y-666853D01*
Y-667019D01*
X428993Y-667103D01*
G01Y-664853D02*
X428866Y-664769D01*
Y-664603D01*
X428993Y-664519D01*
X429120Y-664603D01*
Y-664769D01*
X428993Y-664853D01*
G01X407326Y-641936D02*
Y-636936D01*
X408910D01*
X409416Y-637186D01*
X409733Y-637519D01*
X409860Y-638186D01*
X409733Y-638853D01*
X409353Y-639269D01*
X408910Y-639519D01*
X407326D01*
G01X408910D02*
X409860Y-641936D01*
G01X414960D02*
X412426D01*
Y-636936D01*
X414960D01*
G01X413946Y-639353D02*
X412426D01*
G01X417210Y-636936D02*
X418793Y-641936D01*
X420376Y-636936D01*
G01X423893Y-642103D02*
X423766Y-642019D01*
Y-641853D01*
X423893Y-641769D01*
X424020Y-641853D01*
Y-642019D01*
X423893Y-642103D01*
G01Y-639853D02*
X423766Y-639769D01*
Y-639603D01*
X423893Y-639519D01*
X424020Y-639603D01*
Y-639769D01*
X423893Y-639853D01*
G01X2010999Y-388000D02*
Y1475775D01*
X-407000D01*
Y-386798D01*
Y-755294D01*
Y-793716D01*
X-368578D01*
X1942346D01*
X2010999D01*
Y-725063D01*
Y-388000D01*
G01X-42602Y-671096D02*
X-41975Y-671621D01*
X-41270Y-671936D01*
X-40644D01*
X-40017Y-671621D01*
X-39547Y-671096D01*
X-39312Y-670361D01*
X-39469Y-669626D01*
X-39860Y-668996D01*
X-40565Y-668576D01*
X-41505Y-668366D01*
X-42054Y-667946D01*
X-42289Y-667211D01*
X-42132Y-666476D01*
X-41740Y-665951D01*
X-41192Y-665636D01*
X-40644D01*
X-40095Y-665846D01*
X-39625Y-666371D01*
G01X-36302Y-671936D02*
Y-665636D01*
G01X-33012D02*
Y-671936D01*
G01Y-668786D02*
X-36302D01*
G01X-29297Y-665636D02*
X-27417D01*
G01X-28357D02*
Y-671936D01*
G01X-29297D02*
X-27417D01*
G01X-20490D02*
X-23624D01*
Y-665636D01*
X-20490D01*
G01X-21744Y-668681D02*
X-23624D01*
G01X-17559Y-671936D02*
Y-665636D01*
X-13955Y-671936D01*
Y-665636D01*
G01X-9614Y-673091D02*
X-9300Y-671726D01*
G01X-3157Y-665636D02*
Y-671936D01*
G01X-4959Y-665636D02*
X-1355D01*
G01X1185Y-671936D02*
X3143Y-665636D01*
X5101Y-671936D01*
G01X4396Y-669731D02*
X1890D01*
G01X8503Y-665636D02*
X10383D01*
G01X9443D02*
Y-671936D01*
G01X8503D02*
X10383D01*
G01X13393Y-665636D02*
X14490Y-671936D01*
X15743Y-665636D01*
X16996Y-671936D01*
X18093Y-665636D01*
G01X20085Y-671936D02*
X22043Y-665636D01*
X24001Y-671936D01*
G01X23296Y-669731D02*
X20790D01*
G01X26541Y-671936D02*
Y-665636D01*
X30145Y-671936D01*
Y-665636D01*
G01X39376Y-671936D02*
Y-665636D01*
X41335D01*
X41961Y-665951D01*
X42353Y-666371D01*
X42510Y-667211D01*
X42353Y-668051D01*
X41883Y-668576D01*
X41335Y-668891D01*
X39376D01*
G01X41335D02*
X42510Y-671936D01*
G01X47243Y-672146D02*
X47086Y-672041D01*
Y-671831D01*
X47243Y-671726D01*
X47400Y-671831D01*
Y-672041D01*
X47243Y-672146D01*
G01X53543Y-671936D02*
X52916Y-671831D01*
X52368Y-671411D01*
X51898Y-670781D01*
X51585Y-670046D01*
X51428Y-669206D01*
Y-668366D01*
X51585Y-667526D01*
X51898Y-666791D01*
X52368Y-666161D01*
X52916Y-665741D01*
X53543Y-665636D01*
X54170Y-665741D01*
X54718Y-666161D01*
X55188Y-666791D01*
X55501Y-667526D01*
X55658Y-668366D01*
Y-669206D01*
X55501Y-670046D01*
X55188Y-670781D01*
X54718Y-671411D01*
X54170Y-671831D01*
X53543Y-671936D01*
G01X59843Y-672146D02*
X59686Y-672041D01*
Y-671831D01*
X59843Y-671726D01*
X60000Y-671831D01*
Y-672041D01*
X59843Y-672146D01*
G01X67866Y-666161D02*
X67396Y-665846D01*
X66848Y-665636D01*
X66221D01*
X65516Y-665951D01*
X64968Y-666476D01*
X64576Y-667106D01*
X64263Y-668156D01*
X64185Y-669101D01*
X64341Y-670046D01*
X64576Y-670676D01*
X65046Y-671306D01*
X65595Y-671726D01*
X66143Y-671936D01*
X66691D01*
X67240Y-671726D01*
X67710Y-671411D01*
X68101Y-670991D01*
G01X72443Y-672146D02*
X72286Y-672041D01*
Y-671831D01*
X72443Y-671726D01*
X72600Y-671831D01*
Y-672041D01*
X72443Y-672146D01*
G01X-42680Y-661936D02*
Y-655636D01*
G01X-39704D02*
X-42680Y-659521D01*
G01X-39234Y-661936D02*
X-41349Y-657736D01*
G01X-36380Y-655636D02*
Y-660151D01*
X-36067Y-661096D01*
X-35440Y-661726D01*
X-34657Y-661936D01*
X-33874Y-661726D01*
X-33247Y-661096D01*
X-32934Y-660151D01*
Y-655636D01*
G01X-26790Y-661936D02*
X-29924D01*
Y-655636D01*
X-26790D01*
G01X-28044Y-658681D02*
X-29924D01*
G01X-22997Y-655636D02*
X-21117D01*
G01X-22057D02*
Y-661936D01*
G01X-22997D02*
X-21117D01*
G01X-11102Y-661096D02*
X-10475Y-661621D01*
X-9770Y-661936D01*
X-9144D01*
X-8517Y-661621D01*
X-8047Y-661096D01*
X-7812Y-660361D01*
X-7969Y-659626D01*
X-8360Y-658996D01*
X-9065Y-658576D01*
X-10005Y-658366D01*
X-10554Y-657946D01*
X-10789Y-657211D01*
X-10632Y-656476D01*
X-10240Y-655951D01*
X-9692Y-655636D01*
X-9144D01*
X-8595Y-655846D01*
X-8125Y-656371D01*
G01X-4802Y-661936D02*
Y-655636D01*
G01X-1512D02*
Y-661936D01*
G01Y-658786D02*
X-4802D01*
G01X1185Y-661936D02*
X3143Y-655636D01*
X5101Y-661936D01*
G01X4396Y-659731D02*
X1890D01*
G01X7641Y-661936D02*
Y-655636D01*
X11245Y-661936D01*
Y-655636D01*
G01X20398Y-661936D02*
Y-655636D01*
G01X23688D02*
Y-661936D01*
G01Y-658786D02*
X20398D01*
G01X26698Y-661096D02*
X27325Y-661621D01*
X28030Y-661936D01*
X28656D01*
X29283Y-661621D01*
X29753Y-661096D01*
X29988Y-660361D01*
X29831Y-659626D01*
X29440Y-658996D01*
X28735Y-658576D01*
X27795Y-658366D01*
X27246Y-657946D01*
X27011Y-657211D01*
X27168Y-656476D01*
X27560Y-655951D01*
X28108Y-655636D01*
X28656D01*
X29205Y-655846D01*
X29675Y-656371D01*
G01X33703Y-655636D02*
X35583D01*
G01X34643D02*
Y-661936D01*
G01X33703D02*
X35583D01*
G01X38985D02*
X40943Y-655636D01*
X42901Y-661936D01*
G01X42196Y-659731D02*
X39690D01*
G01X45441Y-661936D02*
Y-655636D01*
X49045Y-661936D01*
Y-655636D01*
G01X54013Y-658786D02*
X55580D01*
Y-660676D01*
X55110Y-661306D01*
X54561Y-661726D01*
X53778Y-661936D01*
X52995Y-661726D01*
X52446Y-661306D01*
X51976Y-660676D01*
X51663Y-659941D01*
X51506Y-659101D01*
Y-658366D01*
X51663Y-657736D01*
X51976Y-657001D01*
X52446Y-656371D01*
X52916Y-655951D01*
X53543Y-655636D01*
X54091D01*
X54718Y-655846D01*
X55188Y-656266D01*
G01X59686Y-663091D02*
X60000Y-661726D01*
G01X66143Y-655636D02*
Y-661936D01*
G01X64341Y-655636D02*
X67945D01*
G01X70485Y-661936D02*
X72443Y-655636D01*
X74401Y-661936D01*
G01X73696Y-659731D02*
X71190D01*
G01X78743Y-661936D02*
X78116Y-661831D01*
X77568Y-661411D01*
X77098Y-660781D01*
X76785Y-660046D01*
X76628Y-659206D01*
Y-658366D01*
X76785Y-657526D01*
X77098Y-656791D01*
X77568Y-656161D01*
X78116Y-655741D01*
X78743Y-655636D01*
X79370Y-655741D01*
X79918Y-656161D01*
X80388Y-656791D01*
X80701Y-657526D01*
X80858Y-658366D01*
Y-659206D01*
X80701Y-660046D01*
X80388Y-660781D01*
X79918Y-661411D01*
X79370Y-661831D01*
X78743Y-661936D01*
G01X91343D02*
Y-659101D01*
X89776Y-655636D01*
G01X92910D02*
X91343Y-659101D01*
G01X95920Y-655636D02*
Y-660151D01*
X96233Y-661096D01*
X96860Y-661726D01*
X97643Y-661936D01*
X98426Y-661726D01*
X99053Y-661096D01*
X99366Y-660151D01*
Y-655636D01*
G01X101985Y-661936D02*
X103943Y-655636D01*
X105901Y-661936D01*
G01X105196Y-659731D02*
X102690D01*
G01X108441Y-661936D02*
Y-655636D01*
X112045Y-661936D01*
Y-655636D01*
G01X-42759Y-651936D02*
Y-645636D01*
X-39155Y-651936D01*
Y-645636D01*
G01X-34657Y-651936D02*
X-35284Y-651831D01*
X-35832Y-651411D01*
X-36302Y-650781D01*
X-36615Y-650046D01*
X-36772Y-649206D01*
Y-648366D01*
X-36615Y-647526D01*
X-36302Y-646791D01*
X-35832Y-646161D01*
X-35284Y-645741D01*
X-34657Y-645636D01*
X-34030Y-645741D01*
X-33482Y-646161D01*
X-33012Y-646791D01*
X-32699Y-647526D01*
X-32542Y-648366D01*
Y-649206D01*
X-32699Y-650046D01*
X-33012Y-650781D01*
X-33482Y-651411D01*
X-34030Y-651831D01*
X-34657Y-651936D01*
G01X-28357Y-652146D02*
X-28514Y-652041D01*
Y-651831D01*
X-28357Y-651726D01*
X-28200Y-651831D01*
Y-652041D01*
X-28357Y-652146D01*
G01X-22057Y-651936D02*
Y-645636D01*
X-22997Y-646896D01*
G01Y-651936D02*
X-21117D01*
G01X-15757D02*
X-15209Y-651831D01*
X-14582Y-651516D01*
X-14190Y-650991D01*
X-14034Y-650256D01*
X-14190Y-649521D01*
X-14660Y-648891D01*
X-15365Y-648576D01*
X-16149D01*
X-16619Y-648366D01*
X-17010Y-647841D01*
X-17167Y-647106D01*
X-16932Y-646371D01*
X-16384Y-645846D01*
X-15757Y-645636D01*
X-15130Y-645846D01*
X-14582Y-646371D01*
X-14347Y-647106D01*
X-14504Y-647841D01*
X-14895Y-648366D01*
X-15365Y-648576D01*
X-16149D01*
X-16854Y-648891D01*
X-17324Y-649521D01*
X-17480Y-650256D01*
X-17324Y-650991D01*
X-16932Y-651516D01*
X-16305Y-651831D01*
X-15757Y-651936D01*
G01X-9457D02*
X-8909Y-651831D01*
X-8282Y-651516D01*
X-7890Y-650991D01*
X-7734Y-650256D01*
X-7890Y-649521D01*
X-8360Y-648891D01*
X-9065Y-648576D01*
X-9849D01*
X-10319Y-648366D01*
X-10710Y-647841D01*
X-10867Y-647106D01*
X-10632Y-646371D01*
X-10084Y-645846D01*
X-9457Y-645636D01*
X-8830Y-645846D01*
X-8282Y-646371D01*
X-8047Y-647106D01*
X-8204Y-647841D01*
X-8595Y-648366D01*
X-9065Y-648576D01*
X-9849D01*
X-10554Y-648891D01*
X-11024Y-649521D01*
X-11180Y-650256D01*
X-11024Y-650991D01*
X-10632Y-651516D01*
X-10005Y-651831D01*
X-9457Y-651936D01*
G01X-3314Y-653091D02*
X-3000Y-651726D01*
G01X793Y-645636D02*
X1890Y-651936D01*
X3143Y-645636D01*
X4396Y-651936D01*
X5493Y-645636D01*
G01X11010Y-651936D02*
X7876D01*
Y-645636D01*
X11010D01*
G01X9756Y-648681D02*
X7876D01*
G01X13941Y-651936D02*
Y-645636D01*
X17545Y-651936D01*
Y-645636D01*
G01X26698Y-651936D02*
Y-645636D01*
G01X29988D02*
Y-651936D01*
G01Y-648786D02*
X26698D01*
G01X32293Y-645636D02*
X33390Y-651936D01*
X34643Y-645636D01*
X35896Y-651936D01*
X36993Y-645636D01*
G01X38985Y-651936D02*
X40943Y-645636D01*
X42901Y-651936D01*
G01X42196Y-649731D02*
X39690D01*
G01X52055Y-646686D02*
X52525Y-646056D01*
X53073Y-645741D01*
X53700Y-645636D01*
X54483Y-645846D01*
X55031Y-646371D01*
X55188Y-647001D01*
X55110Y-647631D01*
X54796Y-648156D01*
X53230Y-649206D01*
X52525Y-649941D01*
X52055Y-650991D01*
X51898Y-651936D01*
X55188D01*
G01X58041D02*
Y-645636D01*
X61645Y-651936D01*
Y-645636D01*
G01X64420Y-651936D02*
Y-645636D01*
X65986D01*
X66613Y-645951D01*
X67083Y-646371D01*
X67475Y-647001D01*
X67788Y-647736D01*
X67866Y-648786D01*
X67788Y-649836D01*
X67475Y-650571D01*
X67083Y-651201D01*
X66613Y-651621D01*
X65986Y-651936D01*
X64420D01*
G01X77176D02*
Y-645636D01*
X79135D01*
X79761Y-645951D01*
X80153Y-646371D01*
X80310Y-647211D01*
X80153Y-648051D01*
X79683Y-648576D01*
X79135Y-648891D01*
X77176D01*
G01X79135D02*
X80310Y-651936D01*
G01X83320D02*
Y-645636D01*
X84886D01*
X85513Y-645951D01*
X85983Y-646371D01*
X86375Y-647001D01*
X86688Y-647736D01*
X86766Y-648786D01*
X86688Y-649836D01*
X86375Y-650571D01*
X85983Y-651201D01*
X85513Y-651621D01*
X84886Y-651936D01*
X83320D01*
G01X91343Y-652146D02*
X91186Y-652041D01*
Y-651831D01*
X91343Y-651726D01*
X91500Y-651831D01*
Y-652041D01*
X91343Y-652146D01*
G01X-18657Y-639236D02*
X-21177Y-638819D01*
X-23382Y-637153D01*
X-25272Y-634653D01*
X-26532Y-631736D01*
X-27162Y-628403D01*
Y-625069D01*
X-26532Y-621736D01*
X-25272Y-618819D01*
X-23382Y-616320D01*
X-21177Y-614653D01*
X-18657Y-614236D01*
X-16137Y-614653D01*
X-13932Y-616320D01*
X-12042Y-618819D01*
X-10782Y-621736D01*
X-10152Y-625069D01*
Y-628403D01*
X-10782Y-631736D01*
X-12042Y-634653D01*
X-13932Y-637153D01*
X-16137Y-638819D01*
X-18657Y-639236D01*
G01X-16137Y-632569D02*
X-12357Y-639236D01*
G01X1188Y-622570D02*
Y-634236D01*
X2448Y-637153D01*
X4338Y-638819D01*
X6543Y-639236D01*
X8748Y-638819D01*
X10638Y-637153D01*
X11898Y-634236D01*
G01Y-639236D02*
Y-622570D01*
G01X37413Y-639236D02*
Y-622570D01*
G01Y-625486D02*
X36153Y-623820D01*
X34263Y-622986D01*
X32058Y-622570D01*
X29853Y-623403D01*
X27963Y-625069D01*
X26703Y-627570D01*
X26073Y-630903D01*
X26703Y-634236D01*
X27963Y-636737D01*
X29853Y-638403D01*
X32058Y-639236D01*
X34263Y-638819D01*
X36153Y-637570D01*
X37413Y-635903D01*
G01X51588Y-639236D02*
Y-622570D01*
G01Y-626736D02*
X52848Y-624653D01*
X54738Y-622986D01*
X57258Y-622570D01*
X59463Y-622986D01*
X61353Y-624653D01*
X62298Y-627570D01*
Y-639236D01*
G01X82143Y-614236D02*
Y-639236D01*
G01X77733Y-622570D02*
X86553D01*
G01X113013Y-639236D02*
Y-622570D01*
G01Y-625486D02*
X111753Y-623820D01*
X109863Y-622986D01*
X107658Y-622570D01*
X105453Y-623403D01*
X103563Y-625069D01*
X102303Y-627570D01*
X101673Y-630903D01*
X102303Y-634236D01*
X103563Y-636737D01*
X105453Y-638403D01*
X107658Y-639236D01*
X109863Y-638819D01*
X111753Y-637570D01*
X113013Y-635903D01*
G01X152693Y-618936D02*
Y-626936D01*
X156693D01*
G01X164493D02*
Y-621603D01*
G01Y-622536D02*
X164093Y-622003D01*
X163493Y-621736D01*
X162793Y-621603D01*
X162093Y-621869D01*
X161493Y-622403D01*
X161093Y-623203D01*
X160893Y-624269D01*
X161093Y-625336D01*
X161493Y-626136D01*
X162093Y-626669D01*
X162793Y-626936D01*
X163493Y-626803D01*
X164093Y-626403D01*
X164493Y-625870D01*
G01X168593Y-629336D02*
X169193Y-629603D01*
X169993Y-629336D01*
X170493Y-628803D01*
X170893Y-628136D01*
X171493Y-626003D01*
X172793Y-621603D01*
G01X169593D02*
X171493Y-626003D01*
G01X177193Y-623336D02*
X180393D01*
X180093Y-622403D01*
X179593Y-621869D01*
X178893Y-621603D01*
X178193Y-621736D01*
X177593Y-622136D01*
X177193Y-623069D01*
X176993Y-623870D01*
Y-624669D01*
X177193Y-625469D01*
X177693Y-626269D01*
X178293Y-626803D01*
X178993Y-626936D01*
X179693Y-626669D01*
X180393Y-625870D01*
G01X185293Y-626936D02*
Y-621603D01*
G01Y-622669D02*
X185793Y-622136D01*
X186293Y-621736D01*
X186993Y-621603D01*
X187493Y-621736D01*
X188093Y-622136D01*
G01X173993Y-676936D02*
Y-668936D01*
G01X177793D02*
X173993Y-673870D01*
G01X178393Y-676936D02*
X175693Y-671603D01*
G01X185993Y-676936D02*
Y-671603D01*
G01Y-672536D02*
X185593Y-672003D01*
X184993Y-671736D01*
X184293Y-671603D01*
X183593Y-671869D01*
X182993Y-672403D01*
X182593Y-673203D01*
X182393Y-674269D01*
X182593Y-675336D01*
X182993Y-676136D01*
X183593Y-676669D01*
X184293Y-676936D01*
X184993Y-676803D01*
X185593Y-676403D01*
X185993Y-675870D01*
G01X192193Y-671603D02*
Y-676936D01*
G01Y-669469D02*
X191993Y-669336D01*
Y-669069D01*
X192193Y-668936D01*
X192393Y-669069D01*
Y-669336D01*
X192193Y-669469D01*
G01X183693Y-643936D02*
X186193Y-651936D01*
X188693Y-643936D01*
G01X196393Y-644603D02*
X195793Y-644203D01*
X195093Y-643936D01*
X194293D01*
X193393Y-644336D01*
X192693Y-645003D01*
X192193Y-645803D01*
X191793Y-647136D01*
X191693Y-648336D01*
X191893Y-649536D01*
X192193Y-650336D01*
X192793Y-651136D01*
X193493Y-651669D01*
X194193Y-651936D01*
X194893D01*
X195593Y-651669D01*
X196193Y-651269D01*
X196693Y-650736D01*
G01X204393Y-644603D02*
X203793Y-644203D01*
X203093Y-643936D01*
X202293D01*
X201393Y-644336D01*
X200693Y-645003D01*
X200193Y-645803D01*
X199793Y-647136D01*
X199693Y-648336D01*
X199893Y-649536D01*
X200193Y-650336D01*
X200793Y-651136D01*
X201493Y-651669D01*
X202193Y-651936D01*
X202893D01*
X203593Y-651669D01*
X204193Y-651269D01*
X204693Y-650736D01*
G01X210193Y-651936D02*
Y-643936D01*
X208993Y-645536D01*
G01Y-651936D02*
X211393D01*
G01X205993Y-626936D02*
X206193Y-625203D01*
X206493Y-623736D01*
X206893Y-622403D01*
X207393Y-620936D01*
X208193Y-618936D01*
X204193D01*
G01X279293Y-670269D02*
X279893Y-669469D01*
X280593Y-669069D01*
X281393Y-668936D01*
X282393Y-669203D01*
X283093Y-669869D01*
X283293Y-670669D01*
X283193Y-671470D01*
X282793Y-672136D01*
X280793Y-673469D01*
X279893Y-674403D01*
X279293Y-675736D01*
X279093Y-676936D01*
X283293D01*
G01X289193Y-668936D02*
X288393Y-669203D01*
X287793Y-669869D01*
X287393Y-670669D01*
X287093Y-671736D01*
X286993Y-672936D01*
X287093Y-674136D01*
X287393Y-675203D01*
X287793Y-676003D01*
X288393Y-676669D01*
X289193Y-676936D01*
X289993Y-676669D01*
X290593Y-676003D01*
X290993Y-675203D01*
X291293Y-674136D01*
X291393Y-672936D01*
X291293Y-671736D01*
X290993Y-670669D01*
X290593Y-669869D01*
X289993Y-669203D01*
X289193Y-668936D01*
G01X295293Y-670269D02*
X295893Y-669469D01*
X296593Y-669069D01*
X297393Y-668936D01*
X298393Y-669203D01*
X299093Y-669869D01*
X299293Y-670669D01*
X299193Y-671470D01*
X298793Y-672136D01*
X296793Y-673469D01*
X295893Y-674403D01*
X295293Y-675736D01*
X295093Y-676936D01*
X299293D01*
G01X303293Y-670269D02*
X303893Y-669469D01*
X304593Y-669069D01*
X305393Y-668936D01*
X306393Y-669203D01*
X307093Y-669869D01*
X307293Y-670669D01*
X307193Y-671470D01*
X306793Y-672136D01*
X304793Y-673469D01*
X303893Y-674403D01*
X303293Y-675736D01*
X303093Y-676936D01*
X307293D01*
G01X311393Y-677203D02*
X314993Y-668936D01*
G01X321193Y-676936D02*
Y-668936D01*
X319993Y-670536D01*
G01Y-676936D02*
X322393D01*
G01X327293Y-670269D02*
X327893Y-669469D01*
X328593Y-669069D01*
X329393Y-668936D01*
X330393Y-669203D01*
X331093Y-669869D01*
X331293Y-670669D01*
X331193Y-671470D01*
X330793Y-672136D01*
X328793Y-673469D01*
X327893Y-674403D01*
X327293Y-675736D01*
X327093Y-676936D01*
X331293D01*
G01X335393Y-677203D02*
X338993Y-668936D01*
G01X345193D02*
X344393Y-669203D01*
X343793Y-669869D01*
X343393Y-670669D01*
X343093Y-671736D01*
X342993Y-672936D01*
X343093Y-674136D01*
X343393Y-675203D01*
X343793Y-676003D01*
X344393Y-676669D01*
X345193Y-676936D01*
X345993Y-676669D01*
X346593Y-676003D01*
X346993Y-675203D01*
X347293Y-674136D01*
X347393Y-672936D01*
X347293Y-671736D01*
X346993Y-670669D01*
X346593Y-669869D01*
X345993Y-669203D01*
X345193Y-668936D01*
G01X351493Y-676003D02*
X352193Y-676669D01*
X352993Y-676936D01*
X353793Y-676669D01*
X354493Y-675870D01*
X354993Y-674669D01*
X355193Y-673469D01*
Y-672003D01*
X354993Y-670803D01*
X354493Y-669736D01*
X353893Y-669203D01*
X353193Y-668936D01*
X352393Y-669203D01*
X351793Y-669736D01*
X351393Y-670536D01*
X351193Y-671603D01*
X351393Y-672536D01*
X351893Y-673469D01*
X352493Y-674003D01*
X353193Y-674136D01*
X353993Y-673870D01*
X354593Y-673203D01*
X355193Y-672003D01*
G01X278993Y-651936D02*
Y-643936D01*
X280993D01*
X281793Y-644336D01*
X282393Y-644869D01*
X282893Y-645669D01*
X283293Y-646603D01*
X283393Y-647936D01*
X283293Y-649269D01*
X282893Y-650203D01*
X282393Y-651003D01*
X281793Y-651536D01*
X280993Y-651936D01*
X278993D01*
G01X286693D02*
X289193Y-643936D01*
X291693Y-651936D01*
G01X290793Y-649136D02*
X287593D01*
G01X297193Y-643936D02*
X296393Y-644203D01*
X295793Y-644869D01*
X295393Y-645669D01*
X295093Y-646736D01*
X294993Y-647936D01*
X295093Y-649136D01*
X295393Y-650203D01*
X295793Y-651003D01*
X296393Y-651669D01*
X297193Y-651936D01*
X297993Y-651669D01*
X298593Y-651003D01*
X298993Y-650203D01*
X299293Y-649136D01*
X299393Y-647936D01*
X299293Y-646736D01*
X298993Y-645669D01*
X298593Y-644869D01*
X297993Y-644203D01*
X297193Y-643936D01*
G01X303293Y-651936D02*
Y-643936D01*
X307093D01*
G01X305693Y-647803D02*
X303293D01*
G01X313193Y-643936D02*
X312393Y-644203D01*
X311793Y-644869D01*
X311393Y-645669D01*
X311093Y-646736D01*
X310993Y-647936D01*
X311093Y-649136D01*
X311393Y-650203D01*
X311793Y-651003D01*
X312393Y-651669D01*
X313193Y-651936D01*
X313993Y-651669D01*
X314593Y-651003D01*
X314993Y-650203D01*
X315293Y-649136D01*
X315393Y-647936D01*
X315293Y-646736D01*
X314993Y-645669D01*
X314593Y-644869D01*
X313993Y-644203D01*
X313193Y-643936D01*
G01X321193D02*
Y-651936D01*
G01X318893Y-643936D02*
X323493D01*
G01X326593Y-651936D02*
Y-643936D01*
X329193Y-650603D01*
X331793Y-643936D01*
Y-651936D01*
G01X334993D02*
Y-643936D01*
X336993D01*
X337793Y-644336D01*
X338393Y-644869D01*
X338893Y-645669D01*
X339293Y-646603D01*
X339393Y-647936D01*
X339293Y-649269D01*
X338893Y-650203D01*
X338393Y-651003D01*
X337793Y-651536D01*
X336993Y-651936D01*
X334993D01*
G01X347393Y-644603D02*
X346793Y-644203D01*
X346093Y-643936D01*
X345293D01*
X344393Y-644336D01*
X343693Y-645003D01*
X343193Y-645803D01*
X342793Y-647136D01*
X342693Y-648336D01*
X342893Y-649536D01*
X343193Y-650336D01*
X343793Y-651136D01*
X344493Y-651669D01*
X345193Y-651936D01*
X345893D01*
X346593Y-651669D01*
X347193Y-651269D01*
X347693Y-650736D01*
G01X350993Y-651936D02*
Y-643936D01*
X352993D01*
X353793Y-644336D01*
X354393Y-644869D01*
X354893Y-645669D01*
X355293Y-646603D01*
X355393Y-647936D01*
X355293Y-649269D01*
X354893Y-650203D01*
X354393Y-651003D01*
X353793Y-651536D01*
X352993Y-651936D01*
X350993D01*
G01X361193Y-643936D02*
X360393Y-644203D01*
X359793Y-644869D01*
X359393Y-645669D01*
X359093Y-646736D01*
X358993Y-647936D01*
X359093Y-649136D01*
X359393Y-650203D01*
X359793Y-651003D01*
X360393Y-651669D01*
X361193Y-651936D01*
X361993Y-651669D01*
X362593Y-651003D01*
X362993Y-650203D01*
X363293Y-649136D01*
X363393Y-647936D01*
X363293Y-646736D01*
X362993Y-645669D01*
X362593Y-644869D01*
X361993Y-644203D01*
X361193Y-643936D01*
G01X298418Y-624819D02*
Y-618519D01*
X301394D01*
G01X300298Y-621564D02*
X298418D01*
G01X306206Y-618519D02*
X305579Y-618729D01*
X305109Y-619254D01*
X304796Y-619884D01*
X304561Y-620724D01*
X304483Y-621669D01*
X304561Y-622614D01*
X304796Y-623454D01*
X305109Y-624084D01*
X305579Y-624609D01*
X306206Y-624819D01*
X306833Y-624609D01*
X307303Y-624084D01*
X307616Y-623454D01*
X307851Y-622614D01*
X307929Y-621669D01*
X307851Y-620724D01*
X307616Y-619884D01*
X307303Y-619254D01*
X306833Y-618729D01*
X306206Y-618519D01*
G01X312506D02*
Y-624819D01*
G01X310704Y-618519D02*
X314308D01*
G01X316456Y-626919D02*
X321156D01*
G01X323069Y-624819D02*
Y-618519D01*
X325106Y-623769D01*
X327143Y-618519D01*
Y-624819D01*
G01X332816D02*
Y-620619D01*
G01Y-621354D02*
X332503Y-620934D01*
X332033Y-620724D01*
X331484Y-620619D01*
X330936Y-620829D01*
X330466Y-621249D01*
X330153Y-621879D01*
X329996Y-622719D01*
X330153Y-623559D01*
X330466Y-624189D01*
X330936Y-624609D01*
X331484Y-624819D01*
X332033Y-624714D01*
X332503Y-624399D01*
X332816Y-623979D01*
G01X336374Y-624819D02*
Y-620619D01*
G01Y-621669D02*
X336688Y-621144D01*
X337158Y-620724D01*
X337784Y-620619D01*
X338333Y-620724D01*
X338803Y-621144D01*
X339038Y-621879D01*
Y-624819D01*
G01X345416D02*
Y-620619D01*
G01Y-621354D02*
X345103Y-620934D01*
X344633Y-620724D01*
X344084Y-620619D01*
X343536Y-620829D01*
X343066Y-621249D01*
X342753Y-621879D01*
X342596Y-622719D01*
X342753Y-623559D01*
X343066Y-624189D01*
X343536Y-624609D01*
X344084Y-624819D01*
X344633Y-624714D01*
X345103Y-624399D01*
X345416Y-623979D01*
G01X349209Y-626394D02*
X349758Y-626814D01*
X350384Y-626919D01*
X350933Y-626814D01*
X351403Y-626289D01*
X351716Y-625554D01*
Y-620619D01*
G01Y-621459D02*
X351403Y-621039D01*
X350933Y-620724D01*
X350384Y-620619D01*
X349758Y-620829D01*
X349366Y-621249D01*
X349053Y-621984D01*
X348896Y-622719D01*
X348974Y-623349D01*
X349288Y-624084D01*
X349758Y-624609D01*
X350384Y-624819D01*
X350854Y-624714D01*
X351403Y-624294D01*
X351716Y-623874D01*
G01X355431Y-621984D02*
X357938D01*
X357703Y-621249D01*
X357311Y-620829D01*
X356763Y-620619D01*
X356214Y-620724D01*
X355744Y-621039D01*
X355431Y-621774D01*
X355274Y-622404D01*
Y-623034D01*
X355431Y-623664D01*
X355823Y-624294D01*
X356293Y-624714D01*
X356841Y-624819D01*
X357389Y-624609D01*
X357938Y-623979D01*
G01X360556Y-624819D02*
Y-620619D01*
G01Y-621774D02*
X360791Y-621249D01*
X361183Y-620829D01*
X361731Y-620619D01*
X362279Y-620829D01*
X362671Y-621249D01*
X362906Y-621774D01*
Y-624819D01*
G01Y-621774D02*
X363141Y-621249D01*
X363533Y-620829D01*
X364081Y-620619D01*
X364629Y-620829D01*
X365021Y-621249D01*
X365256Y-621879D01*
Y-624819D01*
G01X368031Y-621984D02*
X370538D01*
X370303Y-621249D01*
X369911Y-620829D01*
X369363Y-620619D01*
X368814Y-620724D01*
X368344Y-621039D01*
X368031Y-621774D01*
X367874Y-622404D01*
Y-623034D01*
X368031Y-623664D01*
X368423Y-624294D01*
X368893Y-624714D01*
X369441Y-624819D01*
X369989Y-624609D01*
X370538Y-623979D01*
G01X374174Y-624819D02*
Y-620619D01*
G01Y-621669D02*
X374488Y-621144D01*
X374958Y-620724D01*
X375584Y-620619D01*
X376133Y-620724D01*
X376603Y-621144D01*
X376838Y-621879D01*
Y-624819D01*
G01X381806Y-618519D02*
Y-624819D01*
G01X380709Y-620619D02*
X382903D01*
G01X385756Y-626919D02*
X390456D01*
G01X395033Y-621459D02*
X395346Y-621144D01*
X395581Y-620619D01*
X395738Y-619884D01*
X395581Y-619254D01*
X395268Y-618834D01*
X394719Y-618519D01*
X392604D01*
Y-624819D01*
X395189D01*
X395738Y-624399D01*
X396051Y-623769D01*
X396208Y-623034D01*
X396051Y-622299D01*
X395581Y-621669D01*
X395033Y-621459D01*
X392604D01*
G01X398983Y-624819D02*
Y-618519D01*
X400549D01*
X401176Y-618834D01*
X401646Y-619254D01*
X402038Y-619884D01*
X402351Y-620619D01*
X402429Y-621669D01*
X402351Y-622719D01*
X402038Y-623454D01*
X401646Y-624084D01*
X401176Y-624504D01*
X400549Y-624819D01*
X398983D01*
G01X367693Y-679936D02*
Y-671936D01*
X366493Y-673536D01*
G01Y-679936D02*
X368893D01*
G01X373793Y-676603D02*
X374493Y-675669D01*
X375093Y-675136D01*
X375893Y-674869D01*
X376593Y-675136D01*
X377093Y-675669D01*
X377493Y-676469D01*
X377593Y-677403D01*
X377493Y-678203D01*
X377093Y-679003D01*
X376493Y-679669D01*
X375793Y-679936D01*
X374993Y-679669D01*
X374293Y-678870D01*
X373893Y-677669D01*
X373793Y-676336D01*
X373993Y-674603D01*
X374293Y-673669D01*
X374793Y-672736D01*
X375493Y-672069D01*
X376193Y-671936D01*
X376893Y-672203D01*
X377393Y-672869D01*
G01X383693Y-680203D02*
X383493Y-680069D01*
Y-679803D01*
X383693Y-679669D01*
X383893Y-679803D01*
Y-680069D01*
X383693Y-680203D01*
G01X389793Y-676603D02*
X390493Y-675669D01*
X391093Y-675136D01*
X391893Y-674869D01*
X392593Y-675136D01*
X393093Y-675669D01*
X393493Y-676469D01*
X393593Y-677403D01*
X393493Y-678203D01*
X393093Y-679003D01*
X392493Y-679669D01*
X391793Y-679936D01*
X390993Y-679669D01*
X390293Y-678870D01*
X389893Y-677669D01*
X389793Y-676336D01*
X389993Y-674603D01*
X390293Y-673669D01*
X390793Y-672736D01*
X391493Y-672069D01*
X392193Y-671936D01*
X392893Y-672203D01*
X393393Y-672869D01*
G01X412693Y-679936D02*
Y-671936D01*
X411493Y-673536D01*
G01Y-679936D02*
X413893D01*
G01X420493D02*
X420693Y-678203D01*
X420993Y-676736D01*
X421393Y-675403D01*
X421893Y-673936D01*
X422693Y-671936D01*
X418693D01*
G01X428693Y-680203D02*
X428493Y-680069D01*
Y-679803D01*
X428693Y-679669D01*
X428893Y-679803D01*
Y-680069D01*
X428693Y-680203D01*
G01X434793Y-673269D02*
X435393Y-672469D01*
X436093Y-672069D01*
X436893Y-671936D01*
X437893Y-672203D01*
X438593Y-672869D01*
X438793Y-673669D01*
X438693Y-674470D01*
X438293Y-675136D01*
X436293Y-676469D01*
X435393Y-677403D01*
X434793Y-678736D01*
X434593Y-679936D01*
X438793D01*
G01X432493Y-654936D02*
Y-646936D01*
X434493D01*
X435293Y-647336D01*
X435893Y-647869D01*
X436393Y-648669D01*
X436793Y-649603D01*
X436893Y-650936D01*
X436793Y-652269D01*
X436393Y-653203D01*
X435893Y-654003D01*
X435293Y-654536D01*
X434493Y-654936D01*
X432493D01*
M02*
